FILE_TYPE = MACRO_DRAWING;
SET COLOR_WIRE YELLOW;
SET COLOR_PROP ORANGE;
SET COLOR_DOT WHITE;
SET COLOR_ARC YELLOW;
SET COLOR_BODY GREEN;
SET COLOR_NOTE PURPLE;
SET PROP_DISPLAY VALUE;
SET PAGE_NUMBER P194;
FORCEADD UNIVERSAL_GND..1
(1300 875);
FORCEPROP 3 LASTPIN (1300 925) SIG_NAME GND\g
J 0
(1310 935);
DISPLAY 0.659574 (1310 935);
PAINT MONO (1310 935);
DISPLAY INVISIBLE (1310 935);
FORCEPROP 2 LAST CDS_LIB pure_quanta_power
J 0
(1300 875);
PAINT MONO (1300 875);
DISPLAY INVISIBLE (1300 875);
FORCEPROP 1 LAST PATH I1
J 0
(1375 875);
DISPLAY 0.872340 (1375 875);
PAINT AQUA (1375 875);
DISPLAY INVISIBLE (1375 875);
FORCEPROP 1 LAST HDL_POWER GND
J 1
(1325 800);
DISPLAY 0.872340 (1325 800);
PAINT GREEN (1325 800);
DISPLAY INVISIBLE (1325 800);
FORCEADD Q_CAP..1
(800 1225);
FORCEPROP 1 LAST LOCATION PC403_4
J 0
(850 1325);
DISPLAY 0.489362 (850 1325);
PAINT SKYBLUE (850 1325);
FORCEPROP 0 LAST $SEC 1
J 0
(850 1350);
DISPLAY 0.680851 (850 1350);
PAINT MONO (850 1350);
DISPLAY INVISIBLE (850 1350);
FORCEPROP 0 LAST CDS_SEC 1
J 0
(1050 1275);
DISPLAY 1.021277 (1050 1275);
DISPLAY INVISIBLE (1050 1275);
FORCEPROP 1 LASTPIN (800 1325) $PN 1
J 0
(810 1305);
DISPLAY 0.489362 (810 1305);
PAINT MONO (810 1305);
FORCEPROP 1 LASTPIN (800 1125) $PN 2
J 0
(810 1105);
DISPLAY 0.489362 (810 1105);
PAINT MONO (810 1105);
FORCEPROP 1 LAST MATERIAL X7R
J 0
(850 1125);
DISPLAY 0.489362 (850 1125);
PAINT SKYBLUE (850 1125);
FORCEPROP 1 LAST TOLERANCE 10%
J 0
(850 1175);
DISPLAY 0.489362 (850 1175);
PAINT SKYBLUE (850 1175);
FORCEPROP 1 LAST VALUE 0.1UF
J 0
(850 1275);
DISPLAY 0.489362 (850 1275);
PAINT SKYBLUE (850 1275);
FORCEPROP 1 LAST PART_NUMBER CH4104K1B00
J 0
(850 1075);
DISPLAY 0.489362 (850 1075);
PAINT SKYBLUE (850 1075);
FORCEPROP 1 LAST VOLTAGE 25V
J 0
(850 1225);
DISPLAY 0.489362 (850 1225);
PAINT SKYBLUE (850 1225);
FORCEPROP 1 LAST PACK_TYPE 0402
J 0
(850 1025);
DISPLAY 0.489362 (850 1025);
PAINT SKYBLUE (850 1025);
FORCEPROP 2 LAST CDS_LIB pure_quanta
J 0
(800 1225);
DISPLAY INVISIBLE (800 1225);
FORCEPROP 1 LAST PATH I100
J 0
(850 1375);
DISPLAY 0.978723 (850 1375);
PAINT WHITE (850 1375);
DISPLAY INVISIBLE (850 1375);
FORCEADD Q_CAP..1
(5600 4650);
FORCEPROP 1 LAST LOCATION PC414
J 0
(5650 4750);
DISPLAY 0.489362 (5650 4750);
PAINT SKYBLUE (5650 4750);
FORCEPROP 0 LAST $SEC 1
J 0
(5650 4800);
DISPLAY 0.680851 (5650 4800);
PAINT MONO (5650 4800);
DISPLAY INVISIBLE (5650 4800);
FORCEPROP 0 LAST CDS_SEC 1
J 2
(5650 4775);
DISPLAY 1.021277 (5650 4775);
DISPLAY INVISIBLE (5650 4775);
FORCEPROP 1 LASTPIN (5600 4750) $PN 1
J 0
(5610 4730);
DISPLAY 0.489362 (5610 4730);
PAINT MONO (5610 4730);
FORCEPROP 1 LASTPIN (5600 4550) $PN 2
J 0
(5610 4530);
DISPLAY 0.489362 (5610 4530);
PAINT MONO (5610 4530);
FORCEPROP 1 LAST MATERIAL X7R
J 0
(5650 4550);
DISPLAY 0.489362 (5650 4550);
PAINT SKYBLUE (5650 4550);
FORCEPROP 1 LAST TOLERANCE 10%
J 0
(5650 4600);
DISPLAY 0.489362 (5650 4600);
PAINT SKYBLUE (5650 4600);
FORCEPROP 1 LAST VALUE 0.22UF
J 0
(5650 4700);
DISPLAY 0.489362 (5650 4700);
PAINT SKYBLUE (5650 4700);
FORCEPROP 1 LAST PART_NUMBER CH4223K1B00
J 0
(5650 4500);
DISPLAY 0.489362 (5650 4500);
PAINT SKYBLUE (5650 4500);
FORCEPROP 1 LAST VOLTAGE 16V
J 0
(5650 4650);
DISPLAY 0.489362 (5650 4650);
PAINT SKYBLUE (5650 4650);
FORCEPROP 1 LAST PACK_TYPE 0402
J 0
(5650 4450);
DISPLAY 0.489362 (5650 4450);
PAINT SKYBLUE (5650 4450);
FORCEPROP 2 LAST CDS_LIB pure_quanta
J 2
(5600 4650);
DISPLAY INVISIBLE (5600 4650);
FORCEPROP 1 LAST PATH I101
J 0
(5650 4800);
DISPLAY 0.978723 (5650 4800);
PAINT WHITE (5650 4800);
DISPLAY INVISIBLE (5650 4800);
FORCEADD Q_RES..1
(4625 4775);
FORCEPROP 1 LAST LOCATION PR267
J 0
(4400 4850);
DISPLAY 0.489362 (4400 4850);
PAINT SKYBLUE (4400 4850);
FORCEPROP 0 LAST $SEC 1
J 0
(4900 4875);
DISPLAY 0.680851 (4900 4875);
PAINT MONO (4900 4875);
DISPLAY INVISIBLE (4900 4875);
FORCEPROP 0 LAST CDS_SEC 1
J 0
(4900 4875);
DISPLAY 1.021277 (4900 4875);
DISPLAY INVISIBLE (4900 4875);
FORCEPROP 1 LASTPIN (4525 4775) $PN 1
J 0
(4537 4787);
DISPLAY 0.787234 (4537 4787);
PAINT MONO (4537 4787);
DISPLAY INVISIBLE (4537 4787);
FORCEPROP 1 LASTPIN (4725 4775) $PN 2
J 0
(4687 4787);
DISPLAY 0.787234 (4687 4787);
PAINT MONO (4687 4787);
DISPLAY INVISIBLE (4687 4787);
FORCEPROP 1 LAST PACK_TYPE 0402LF
J 0
(5025 4700);
DISPLAY 0.489362 (5025 4700);
PAINT SKYBLUE (5025 4700);
FORCEPROP 1 LAST TOLERANCE 1%
J 0
(4625 4850);
DISPLAY 0.489362 (4625 4850);
PAINT SKYBLUE (4625 4850);
FORCEPROP 1 LAST MATERIAL CHIP
J 0
(4475 4700);
DISPLAY 0.489362 (4475 4700);
PAINT SKYBLUE (4475 4700);
FORCEPROP 1 LAST WATTAGE 1/16W
J 2
(4900 4850);
DISPLAY 0.489362 (4900 4850);
PAINT SKYBLUE (4900 4850);
FORCEPROP 1 LAST VALUE 4.7
J 2
(4575 4850);
DISPLAY 0.489362 (4575 4850);
PAINT SKYBLUE (4575 4850);
FORCEPROP 1 LAST PART_NUMBER CS-4702FB19
J 0
(4650 4700);
DISPLAY 0.489362 (4650 4700);
PAINT SKYBLUE (4650 4700);
FORCEPROP 1 LAST PATH I102
J 0
(4575 4925);
DISPLAY 0.978723 (4575 4925);
PAINT WHITE (4575 4925);
DISPLAY INVISIBLE (4575 4925);
FORCEPROP 2 LAST CDS_LIB pure_quanta
J 0
(4625 4775);
DISPLAY INVISIBLE (4625 4775);
FORCEADD Q_CAP..1
(5450 1825);
FORCEPROP 1 LAST LOCATION PC413
J 0
(5500 1925);
DISPLAY 0.489362 (5500 1925);
PAINT SKYBLUE (5500 1925);
FORCEPROP 0 LAST $SEC 1
J 0
(5500 1975);
DISPLAY 0.680851 (5500 1975);
PAINT MONO (5500 1975);
DISPLAY INVISIBLE (5500 1975);
FORCEPROP 0 LAST CDS_SEC 1
J 2
(5500 1950);
DISPLAY 1.021277 (5500 1950);
DISPLAY INVISIBLE (5500 1950);
FORCEPROP 1 LASTPIN (5450 1925) $PN 1
J 0
(5460 1905);
DISPLAY 0.489362 (5460 1905);
PAINT MONO (5460 1905);
FORCEPROP 1 LASTPIN (5450 1725) $PN 2
J 0
(5460 1705);
DISPLAY 0.489362 (5460 1705);
PAINT MONO (5460 1705);
FORCEPROP 1 LAST MATERIAL X7R
J 0
(5500 1725);
DISPLAY 0.489362 (5500 1725);
PAINT SKYBLUE (5500 1725);
FORCEPROP 1 LAST TOLERANCE 10%
J 0
(5500 1775);
DISPLAY 0.489362 (5500 1775);
PAINT SKYBLUE (5500 1775);
FORCEPROP 1 LAST VALUE 0.22UF
J 0
(5500 1875);
DISPLAY 0.489362 (5500 1875);
PAINT SKYBLUE (5500 1875);
FORCEPROP 1 LAST PART_NUMBER CH4223K1B00
J 0
(5500 1675);
DISPLAY 0.489362 (5500 1675);
PAINT SKYBLUE (5500 1675);
FORCEPROP 1 LAST VOLTAGE 16V
J 0
(5500 1825);
DISPLAY 0.489362 (5500 1825);
PAINT SKYBLUE (5500 1825);
FORCEPROP 1 LAST PACK_TYPE 0402
J 0
(5500 1625);
DISPLAY 0.489362 (5500 1625);
PAINT SKYBLUE (5500 1625);
FORCEPROP 2 LAST CDS_LIB pure_quanta
J 2
(5450 1825);
DISPLAY INVISIBLE (5450 1825);
FORCEPROP 1 LAST PATH I103
J 0
(5500 1975);
DISPLAY 0.978723 (5500 1975);
PAINT WHITE (5500 1975);
DISPLAY INVISIBLE (5500 1975);
FORCEADD Q_RES..1
(4550 1950);
FORCEPROP 1 LAST LOCATION PR266
J 0
(4325 2025);
DISPLAY 0.489362 (4325 2025);
PAINT SKYBLUE (4325 2025);
FORCEPROP 0 LAST $SEC 1
J 0
(4825 2050);
DISPLAY 0.680851 (4825 2050);
PAINT MONO (4825 2050);
DISPLAY INVISIBLE (4825 2050);
FORCEPROP 0 LAST CDS_SEC 1
J 0
(4825 2050);
DISPLAY 1.021277 (4825 2050);
DISPLAY INVISIBLE (4825 2050);
FORCEPROP 1 LASTPIN (4450 1950) $PN 1
J 0
(4462 1962);
DISPLAY 0.787234 (4462 1962);
PAINT MONO (4462 1962);
DISPLAY INVISIBLE (4462 1962);
FORCEPROP 1 LASTPIN (4650 1950) $PN 2
J 0
(4612 1962);
DISPLAY 0.787234 (4612 1962);
PAINT MONO (4612 1962);
DISPLAY INVISIBLE (4612 1962);
FORCEPROP 1 LAST PACK_TYPE 0402LF
J 0
(4950 1875);
DISPLAY 0.489362 (4950 1875);
PAINT SKYBLUE (4950 1875);
FORCEPROP 1 LAST TOLERANCE 1%
J 0
(4550 2025);
DISPLAY 0.489362 (4550 2025);
PAINT SKYBLUE (4550 2025);
FORCEPROP 1 LAST MATERIAL CHIP
J 0
(4400 1875);
DISPLAY 0.489362 (4400 1875);
PAINT SKYBLUE (4400 1875);
FORCEPROP 1 LAST WATTAGE 1/16W
J 2
(4825 2025);
DISPLAY 0.489362 (4825 2025);
PAINT SKYBLUE (4825 2025);
FORCEPROP 1 LAST VALUE 4.7
J 2
(4500 2025);
DISPLAY 0.489362 (4500 2025);
PAINT SKYBLUE (4500 2025);
FORCEPROP 1 LAST PART_NUMBER CS-4702FB19
J 0
(4575 1875);
DISPLAY 0.489362 (4575 1875);
PAINT SKYBLUE (4575 1875);
FORCEPROP 1 LAST PATH I104
J 0
(4500 2100);
DISPLAY 0.978723 (4500 2100);
PAINT WHITE (4500 2100);
DISPLAY INVISIBLE (4500 2100);
FORCEPROP 2 LAST CDS_LIB pure_quanta
J 0
(4550 1950);
DISPLAY INVISIBLE (4550 1950);
FORCEADD Q_CAP..1
(4075 5375);
FORCEPROP 1 LAST LOCATION PC406_3
J 0
(4125 5475);
DISPLAY 0.489362 (4125 5475);
PAINT SKYBLUE (4125 5475);
FORCEPROP 0 LAST $SEC 1
J 0
(4125 5525);
DISPLAY 0.680851 (4125 5525);
PAINT MONO (4125 5525);
DISPLAY INVISIBLE (4125 5525);
FORCEPROP 0 LAST CDS_SEC 1
J 0
(4125 5525);
DISPLAY 1.021277 (4125 5525);
DISPLAY INVISIBLE (4125 5525);
FORCEPROP 1 LASTPIN (4075 5475) $PN 1
J 0
(4085 5455);
DISPLAY 0.489362 (4085 5455);
PAINT MONO (4085 5455);
FORCEPROP 1 LASTPIN (4075 5275) $PN 2
J 0
(4085 5255);
DISPLAY 0.489362 (4085 5255);
PAINT MONO (4085 5255);
FORCEPROP 1 LAST MATERIAL X7R
J 0
(4125 5275);
DISPLAY 0.489362 (4125 5275);
PAINT SKYBLUE (4125 5275);
FORCEPROP 1 LAST TOLERANCE 10%
J 0
(4125 5325);
DISPLAY 0.489362 (4125 5325);
PAINT SKYBLUE (4125 5325);
FORCEPROP 1 LAST VALUE 0.1UF
J 0
(4125 5425);
DISPLAY 0.489362 (4125 5425);
PAINT SKYBLUE (4125 5425);
FORCEPROP 1 LAST PART_NUMBER CH4104K1B00
J 0
(4125 5225);
DISPLAY 0.489362 (4125 5225);
PAINT SKYBLUE (4125 5225);
FORCEPROP 1 LAST VOLTAGE 25V
J 0
(4125 5375);
DISPLAY 0.489362 (4125 5375);
PAINT SKYBLUE (4125 5375);
FORCEPROP 1 LAST PACK_TYPE 0402
J 0
(4125 5175);
DISPLAY 0.489362 (4125 5175);
PAINT SKYBLUE (4125 5175);
FORCEPROP 2 LAST CDS_LIB pure_quanta
J 0
(4075 5375);
DISPLAY INVISIBLE (4075 5375);
FORCEPROP 1 LAST PATH I105
J 0
(4125 5525);
DISPLAY 0.978723 (4125 5525);
PAINT WHITE (4125 5525);
DISPLAY INVISIBLE (4125 5525);
FORCEADD Q_CAP..1
(4025 2525);
FORCEPROP 1 LAST LOCATION PC405_4
J 0
(4075 2625);
DISPLAY 0.489362 (4075 2625);
PAINT SKYBLUE (4075 2625);
FORCEPROP 0 LAST $SEC 1
J 0
(4075 2675);
DISPLAY 0.680851 (4075 2675);
PAINT MONO (4075 2675);
DISPLAY INVISIBLE (4075 2675);
FORCEPROP 0 LAST CDS_SEC 1
J 0
(4075 2675);
DISPLAY 1.021277 (4075 2675);
DISPLAY INVISIBLE (4075 2675);
FORCEPROP 1 LASTPIN (4025 2625) $PN 1
J 0
(4035 2605);
DISPLAY 0.489362 (4035 2605);
PAINT MONO (4035 2605);
FORCEPROP 1 LASTPIN (4025 2425) $PN 2
J 0
(4035 2405);
DISPLAY 0.489362 (4035 2405);
PAINT MONO (4035 2405);
FORCEPROP 1 LAST MATERIAL X7R
J 0
(4075 2425);
DISPLAY 0.489362 (4075 2425);
PAINT SKYBLUE (4075 2425);
FORCEPROP 1 LAST TOLERANCE 10%
J 0
(4075 2475);
DISPLAY 0.489362 (4075 2475);
PAINT SKYBLUE (4075 2475);
FORCEPROP 1 LAST VALUE 0.1UF
J 0
(4075 2575);
DISPLAY 0.489362 (4075 2575);
PAINT SKYBLUE (4075 2575);
FORCEPROP 1 LAST PART_NUMBER CH4104K1B00
J 0
(4075 2375);
DISPLAY 0.489362 (4075 2375);
PAINT SKYBLUE (4075 2375);
FORCEPROP 1 LAST VOLTAGE 25V
J 0
(4075 2525);
DISPLAY 0.489362 (4075 2525);
PAINT SKYBLUE (4075 2525);
FORCEPROP 1 LAST PACK_TYPE 0402
J 0
(4075 2325);
DISPLAY 0.489362 (4075 2325);
PAINT SKYBLUE (4075 2325);
FORCEPROP 2 LAST CDS_LIB pure_quanta
J 0
(4025 2525);
DISPLAY INVISIBLE (4025 2525);
FORCEPROP 1 LAST PATH I106
J 0
(4075 2675);
DISPLAY 0.978723 (4075 2675);
PAINT WHITE (4075 2675);
DISPLAY INVISIBLE (4075 2675);
FORCEADD Q_CAP..1
(1625 4875);
FORCEPROP 1 LAST LOCATION PC400
J 0
(1675 4975);
DISPLAY 0.489362 (1675 4975);
PAINT SKYBLUE (1675 4975);
FORCEPROP 0 LAST $SEC 1
J 0
(1675 5025);
DISPLAY 0.680851 (1675 5025);
PAINT MONO (1675 5025);
DISPLAY INVISIBLE (1675 5025);
FORCEPROP 0 LAST CDS_SEC 1
J 0
(1675 5025);
DISPLAY 1.021277 (1675 5025);
DISPLAY INVISIBLE (1675 5025);
FORCEPROP 1 LASTPIN (1625 4975) $PN 1
J 0
(1635 4955);
DISPLAY 0.489362 (1635 4955);
PAINT MONO (1635 4955);
FORCEPROP 1 LASTPIN (1625 4775) $PN 2
J 0
(1635 4755);
DISPLAY 0.489362 (1635 4755);
PAINT MONO (1635 4755);
FORCEPROP 1 LAST MATERIAL X6S
J 0
(1675 4775);
DISPLAY 0.489362 (1675 4775);
PAINT SKYBLUE (1675 4775);
FORCEPROP 1 LAST TOLERANCE 10%
J 0
(1675 4825);
DISPLAY 0.489362 (1675 4825);
PAINT SKYBLUE (1675 4825);
FORCEPROP 1 LAST VALUE 2.2UF
J 0
(1675 4925);
DISPLAY 0.489362 (1675 4925);
PAINT SKYBLUE (1675 4925);
FORCEPROP 1 LAST PART_NUMBER CH5222KEB01
J 0
(1675 4725);
DISPLAY 0.489362 (1675 4725);
PAINT SKYBLUE (1675 4725);
FORCEPROP 1 LAST VOLTAGE 10V
J 0
(1675 4875);
DISPLAY 0.489362 (1675 4875);
PAINT SKYBLUE (1675 4875);
FORCEPROP 1 LAST PACK_TYPE C0402
J 0
(1675 4675);
DISPLAY 0.489362 (1675 4675);
PAINT SKYBLUE (1675 4675);
FORCEPROP 2 LAST CDS_LIB pure_quanta
J 0
(1625 4875);
DISPLAY INVISIBLE (1625 4875);
FORCEPROP 1 LAST PATH I107
J 0
(1675 5025);
DISPLAY 0.978723 (1675 5025);
PAINT WHITE (1675 5025);
DISPLAY INVISIBLE (1675 5025);
FORCEADD UNIVERSAL_GND..1
(1625 4675);
FORCEPROP 3 LASTPIN (1625 4725) SIG_NAME GND\g
J 0
(1635 4735);
DISPLAY 0.659574 (1635 4735);
PAINT MONO (1635 4735);
DISPLAY INVISIBLE (1635 4735);
FORCEPROP 2 LAST CDS_LIB pure_quanta_power
J 0
(1625 4675);
DISPLAY INVISIBLE (1625 4675);
FORCEPROP 1 LAST PATH I108
J 0
(1700 4675);
DISPLAY 0.872340 (1700 4675);
PAINT AQUA (1700 4675);
DISPLAY INVISIBLE (1700 4675);
FORCEPROP 1 LAST HDL_POWER GND
J 1
(1650 4600);
DISPLAY 0.872340 (1650 4600);
PAINT GREEN (1650 4600);
DISPLAY INVISIBLE (1650 4600);
FORCEADD UNIVERSAL_GND..1
(1975 5175);
FORCEPROP 3 LASTPIN (1975 5225) SIG_NAME GND\g
J 0
(1985 5235);
DISPLAY 0.659574 (1985 5235);
PAINT MONO (1985 5235);
DISPLAY INVISIBLE (1985 5235);
FORCEPROP 2 LAST CDS_LIB pure_quanta_power
J 0
(1975 5175);
DISPLAY INVISIBLE (1975 5175);
FORCEPROP 1 LAST PATH I109
J 0
(2050 5175);
DISPLAY 0.872340 (2050 5175);
PAINT AQUA (2050 5175);
DISPLAY INVISIBLE (2050 5175);
FORCEPROP 1 LAST HDL_POWER GND
J 1
(2000 5100);
DISPLAY 0.872340 (2000 5100);
PAINT GREEN (2000 5100);
DISPLAY INVISIBLE (2000 5100);
FORCEADD UNIVERSAL_GND..1
(1325 3700);
FORCEPROP 3 LASTPIN (1325 3750) SIG_NAME GND\g
J 0
(1335 3760);
DISPLAY 0.659574 (1335 3760);
PAINT MONO (1335 3760);
DISPLAY INVISIBLE (1335 3760);
FORCEPROP 2 LAST CDS_LIB pure_quanta_power
J 0
(1325 3700);
PAINT MONO (1325 3700);
DISPLAY INVISIBLE (1325 3700);
FORCEPROP 1 LAST PATH I11
J 0
(1400 3700);
DISPLAY 0.872340 (1400 3700);
PAINT AQUA (1400 3700);
DISPLAY INVISIBLE (1400 3700);
FORCEPROP 1 LAST HDL_POWER GND
J 1
(1350 3625);
DISPLAY 0.872340 (1350 3625);
PAINT GREEN (1350 3625);
DISPLAY INVISIBLE (1350 3625);
FORCEADD Q_RES..2
(1625 5425);
FORCEPROP 1 LAST LOCATION PR265
J 0
(1670 5550);
DISPLAY 0.489362 (1670 5550);
PAINT SKYBLUE (1670 5550);
FORCEPROP 0 LAST $SEC 1
J 0
(1675 5600);
DISPLAY 0.680851 (1675 5600);
PAINT MONO (1675 5600);
DISPLAY INVISIBLE (1675 5600);
FORCEPROP 0 LAST CDS_SEC 1
J 0
(1675 5600);
DISPLAY 1.021277 (1675 5600);
DISPLAY INVISIBLE (1675 5600);
FORCEPROP 1 LASTPIN (1625 5525) $PN 1
J 0
(1630 5487);
DISPLAY 0.489362 (1630 5487);
PAINT MONO (1630 5487);
FORCEPROP 1 LASTPIN (1625 5325) $PN 2
J 0
(1630 5335);
DISPLAY 0.489362 (1630 5335);
PAINT MONO (1630 5335);
FORCEPROP 1 LAST WATTAGE 1/16W
J 0
(1675 5400);
DISPLAY 0.489362 (1675 5400);
PAINT SKYBLUE (1675 5400);
FORCEPROP 1 LAST MATERIAL CHIP
J 0
(1675 5350);
DISPLAY 0.489362 (1675 5350);
PAINT SKYBLUE (1675 5350);
FORCEPROP 1 LAST TOLERANCE 1%
J 0
(1675 5450);
DISPLAY 0.489362 (1675 5450);
PAINT SKYBLUE (1675 5450);
FORCEPROP 1 LAST VALUE 2.2
J 0
(1675 5500);
DISPLAY 0.489362 (1675 5500);
PAINT SKYBLUE (1675 5500);
FORCEPROP 1 LAST PART_NUMBER CS-2202FB00
J 0
(1675 5300);
DISPLAY 0.489362 (1675 5300);
PAINT SKYBLUE (1675 5300);
FORCEPROP 1 LAST PACK_TYPE 0402LF
J 0
(1675 5250);
DISPLAY 0.489362 (1675 5250);
PAINT SKYBLUE (1675 5250);
FORCEPROP 2 LAST CDS_LIB pure_quanta
J 0
(1625 5425);
DISPLAY INVISIBLE (1625 5425);
FORCEPROP 1 LAST PATH I110
J 0
(1675 5600);
DISPLAY 0.978723 (1675 5600);
PAINT WHITE (1675 5600);
DISPLAY INVISIBLE (1675 5600);
FORCEADD Q_CAP..1
(1975 5450);
FORCEPROP 1 LAST LOCATION PC402_C1P1_3
J 0
(2025 5550);
DISPLAY 0.489362 (2025 5550);
PAINT SKYBLUE (2025 5550);
FORCEPROP 0 LAST $SEC 1
J 0
(2025 5600);
DISPLAY 0.680851 (2025 5600);
PAINT MONO (2025 5600);
DISPLAY INVISIBLE (2025 5600);
FORCEPROP 0 LAST CDS_SEC 1
J 0
(2025 5600);
DISPLAY 1.021277 (2025 5600);
DISPLAY INVISIBLE (2025 5600);
FORCEPROP 1 LASTPIN (1975 5550) $PN 1
J 0
(1985 5530);
DISPLAY 0.489362 (1985 5530);
PAINT MONO (1985 5530);
FORCEPROP 1 LASTPIN (1975 5350) $PN 2
J 0
(1985 5330);
DISPLAY 0.489362 (1985 5330);
PAINT MONO (1985 5330);
FORCEPROP 1 LAST MATERIAL X6S
J 0
(2025 5350);
DISPLAY 0.489362 (2025 5350);
PAINT SKYBLUE (2025 5350);
FORCEPROP 1 LAST TOLERANCE 10%
J 0
(2025 5400);
DISPLAY 0.489362 (2025 5400);
PAINT SKYBLUE (2025 5400);
FORCEPROP 1 LAST VALUE 2.2UF
J 0
(2025 5500);
DISPLAY 0.489362 (2025 5500);
PAINT SKYBLUE (2025 5500);
FORCEPROP 1 LAST PART_NUMBER CH5222KEB01
J 0
(2025 5300);
DISPLAY 0.489362 (2025 5300);
PAINT SKYBLUE (2025 5300);
FORCEPROP 1 LAST VOLTAGE 10V
J 0
(2025 5450);
DISPLAY 0.489362 (2025 5450);
PAINT SKYBLUE (2025 5450);
FORCEPROP 1 LAST PACK_TYPE C0402
J 0
(2025 5250);
DISPLAY 0.489362 (2025 5250);
PAINT SKYBLUE (2025 5250);
FORCEPROP 2 LAST CDS_LIB pure_quanta
J 0
(1975 5450);
DISPLAY INVISIBLE (1975 5450);
FORCEPROP 1 LAST PATH I111
J 0
(2025 5600);
DISPLAY 0.978723 (2025 5600);
PAINT WHITE (2025 5600);
DISPLAY INVISIBLE (2025 5600);
FORCEADD Q_CAP..1
(1450 2050);
FORCEPROP 1 LAST LOCATION PC399
J 0
(1500 2150);
DISPLAY 0.489362 (1500 2150);
PAINT SKYBLUE (1500 2150);
FORCEPROP 0 LAST $SEC 1
J 0
(1500 2200);
DISPLAY 0.680851 (1500 2200);
PAINT MONO (1500 2200);
DISPLAY INVISIBLE (1500 2200);
FORCEPROP 0 LAST CDS_SEC 1
J 0
(1500 2200);
DISPLAY 1.021277 (1500 2200);
DISPLAY INVISIBLE (1500 2200);
FORCEPROP 1 LASTPIN (1450 2150) $PN 1
J 0
(1460 2130);
DISPLAY 0.489362 (1460 2130);
PAINT MONO (1460 2130);
FORCEPROP 1 LASTPIN (1450 1950) $PN 2
J 0
(1460 1930);
DISPLAY 0.489362 (1460 1930);
PAINT MONO (1460 1930);
FORCEPROP 1 LAST MATERIAL X6S
J 0
(1500 1950);
DISPLAY 0.489362 (1500 1950);
PAINT SKYBLUE (1500 1950);
FORCEPROP 1 LAST TOLERANCE 10%
J 0
(1500 2000);
DISPLAY 0.489362 (1500 2000);
PAINT SKYBLUE (1500 2000);
FORCEPROP 1 LAST VALUE 2.2UF
J 0
(1500 2100);
DISPLAY 0.489362 (1500 2100);
PAINT SKYBLUE (1500 2100);
FORCEPROP 1 LAST PART_NUMBER CH5222KEB01
J 0
(1500 1900);
DISPLAY 0.489362 (1500 1900);
PAINT SKYBLUE (1500 1900);
FORCEPROP 1 LAST VOLTAGE 10V
J 0
(1500 2050);
DISPLAY 0.489362 (1500 2050);
PAINT SKYBLUE (1500 2050);
FORCEPROP 1 LAST PACK_TYPE C0402
J 0
(1500 1850);
DISPLAY 0.489362 (1500 1850);
PAINT SKYBLUE (1500 1850);
FORCEPROP 2 LAST CDS_LIB pure_quanta
J 0
(1450 2050);
DISPLAY INVISIBLE (1450 2050);
FORCEPROP 1 LAST PATH I113
J 0
(1500 2200);
DISPLAY 0.978723 (1500 2200);
PAINT WHITE (1500 2200);
DISPLAY INVISIBLE (1500 2200);
FORCEADD UNIVERSAL_GND..1
(1450 1850);
FORCEPROP 3 LASTPIN (1450 1900) SIG_NAME GND\g
J 0
(1460 1910);
DISPLAY 0.659574 (1460 1910);
PAINT MONO (1460 1910);
DISPLAY INVISIBLE (1460 1910);
FORCEPROP 2 LAST CDS_LIB pure_quanta_power
J 0
(1450 1850);
DISPLAY INVISIBLE (1450 1850);
FORCEPROP 1 LAST PATH I114
J 0
(1525 1850);
DISPLAY 0.872340 (1525 1850);
PAINT AQUA (1525 1850);
DISPLAY INVISIBLE (1525 1850);
FORCEPROP 1 LAST HDL_POWER GND
J 1
(1475 1775);
DISPLAY 0.872340 (1475 1775);
PAINT GREEN (1475 1775);
DISPLAY INVISIBLE (1475 1775);
FORCEADD UNIVERSAL_GND..1
(1800 2350);
FORCEPROP 3 LASTPIN (1800 2400) SIG_NAME GND\g
J 0
(1810 2410);
DISPLAY 0.659574 (1810 2410);
PAINT MONO (1810 2410);
DISPLAY INVISIBLE (1810 2410);
FORCEPROP 2 LAST CDS_LIB pure_quanta_power
J 0
(1800 2350);
DISPLAY INVISIBLE (1800 2350);
FORCEPROP 1 LAST PATH I115
J 0
(1875 2350);
DISPLAY 0.872340 (1875 2350);
PAINT AQUA (1875 2350);
DISPLAY INVISIBLE (1875 2350);
FORCEPROP 1 LAST HDL_POWER GND
J 1
(1825 2275);
DISPLAY 0.872340 (1825 2275);
PAINT GREEN (1825 2275);
DISPLAY INVISIBLE (1825 2275);
FORCEADD Q_RES..2
(1450 2600);
FORCEPROP 1 LAST LOCATION PR264
J 0
(1495 2725);
DISPLAY 0.489362 (1495 2725);
PAINT SKYBLUE (1495 2725);
FORCEPROP 0 LAST $SEC 1
J 0
(1500 2775);
DISPLAY 0.680851 (1500 2775);
PAINT MONO (1500 2775);
DISPLAY INVISIBLE (1500 2775);
FORCEPROP 0 LAST CDS_SEC 1
J 0
(1500 2775);
DISPLAY 1.021277 (1500 2775);
DISPLAY INVISIBLE (1500 2775);
FORCEPROP 1 LASTPIN (1450 2700) $PN 1
J 0
(1455 2662);
DISPLAY 0.489362 (1455 2662);
PAINT MONO (1455 2662);
FORCEPROP 1 LASTPIN (1450 2500) $PN 2
J 0
(1455 2510);
DISPLAY 0.489362 (1455 2510);
PAINT MONO (1455 2510);
FORCEPROP 1 LAST WATTAGE 1/16W
J 0
(1500 2575);
DISPLAY 0.489362 (1500 2575);
PAINT SKYBLUE (1500 2575);
FORCEPROP 1 LAST MATERIAL CHIP
J 0
(1500 2525);
DISPLAY 0.489362 (1500 2525);
PAINT SKYBLUE (1500 2525);
FORCEPROP 1 LAST TOLERANCE 1%
J 0
(1500 2625);
DISPLAY 0.489362 (1500 2625);
PAINT SKYBLUE (1500 2625);
FORCEPROP 1 LAST VALUE 2.2
J 0
(1500 2675);
DISPLAY 0.489362 (1500 2675);
PAINT SKYBLUE (1500 2675);
FORCEPROP 1 LAST PART_NUMBER CS-2202FB00
J 0
(1500 2475);
DISPLAY 0.489362 (1500 2475);
PAINT SKYBLUE (1500 2475);
FORCEPROP 1 LAST PACK_TYPE 0402LF
J 0
(1500 2425);
DISPLAY 0.489362 (1500 2425);
PAINT SKYBLUE (1500 2425);
FORCEPROP 2 LAST CDS_LIB pure_quanta
J 0
(1450 2600);
DISPLAY INVISIBLE (1450 2600);
FORCEPROP 1 LAST PATH I116
J 0
(1500 2775);
DISPLAY 0.978723 (1500 2775);
PAINT WHITE (1500 2775);
DISPLAY INVISIBLE (1500 2775);
FORCEADD Q_CAP..1
(1800 2625);
FORCEPROP 1 LAST LOCATION PC401_C1P1_4
J 0
(1850 2725);
DISPLAY 0.489362 (1850 2725);
PAINT SKYBLUE (1850 2725);
FORCEPROP 0 LAST $SEC 1
J 0
(1850 2775);
DISPLAY 0.680851 (1850 2775);
PAINT MONO (1850 2775);
DISPLAY INVISIBLE (1850 2775);
FORCEPROP 0 LAST CDS_SEC 1
J 0
(1850 2775);
DISPLAY 1.021277 (1850 2775);
DISPLAY INVISIBLE (1850 2775);
FORCEPROP 1 LASTPIN (1800 2725) $PN 1
J 0
(1810 2705);
DISPLAY 0.489362 (1810 2705);
PAINT MONO (1810 2705);
FORCEPROP 1 LASTPIN (1800 2525) $PN 2
J 0
(1810 2505);
DISPLAY 0.489362 (1810 2505);
PAINT MONO (1810 2505);
FORCEPROP 1 LAST MATERIAL X6S
J 0
(1850 2525);
DISPLAY 0.489362 (1850 2525);
PAINT SKYBLUE (1850 2525);
FORCEPROP 1 LAST TOLERANCE 10%
J 0
(1850 2575);
DISPLAY 0.489362 (1850 2575);
PAINT SKYBLUE (1850 2575);
FORCEPROP 1 LAST VALUE 2.2UF
J 0
(1850 2675);
DISPLAY 0.489362 (1850 2675);
PAINT SKYBLUE (1850 2675);
FORCEPROP 1 LAST PART_NUMBER CH5222KEB01
J 0
(1850 2475);
DISPLAY 0.489362 (1850 2475);
PAINT SKYBLUE (1850 2475);
FORCEPROP 1 LAST VOLTAGE 10V
J 0
(1850 2625);
DISPLAY 0.489362 (1850 2625);
PAINT SKYBLUE (1850 2625);
FORCEPROP 1 LAST PACK_TYPE C0402
J 0
(1850 2425);
DISPLAY 0.489362 (1850 2425);
PAINT SKYBLUE (1850 2425);
FORCEPROP 2 LAST CDS_LIB pure_quanta
J 0
(1800 2625);
DISPLAY INVISIBLE (1800 2625);
FORCEPROP 1 LAST PATH I117
J 0
(1850 2775);
DISPLAY 0.978723 (1850 2775);
PAINT WHITE (1850 2775);
DISPLAY INVISIBLE (1850 2775);
FORCEADD UNIVERSAL_GND..1
(825 3850);
FORCEPROP 3 LASTPIN (825 3900) SIG_NAME GND\g
J 0
(835 3910);
DISPLAY 0.659574 (835 3910);
PAINT MONO (835 3910);
DISPLAY INVISIBLE (835 3910);
FORCEPROP 2 LAST CDS_LIB pure_quanta_power
J 0
(825 3850);
DISPLAY INVISIBLE (825 3850);
FORCEPROP 1 LAST PATH I119
J 0
(900 3850);
DISPLAY 0.872340 (900 3850);
PAINT AQUA (900 3850);
DISPLAY INVISIBLE (900 3850);
FORCEPROP 1 LAST HDL_POWER GND
J 1
(850 3775);
DISPLAY 0.872340 (850 3775);
PAINT GREEN (850 3775);
DISPLAY INVISIBLE (850 3775);
FORCEADD UNIVERSAL_GND..1
(800 1025);
FORCEPROP 3 LASTPIN (800 1075) SIG_NAME GND\g
J 0
(810 1085);
DISPLAY 0.659574 (810 1085);
PAINT MONO (810 1085);
DISPLAY INVISIBLE (810 1085);
FORCEPROP 2 LAST CDS_LIB pure_quanta_power
J 0
(800 1025);
DISPLAY INVISIBLE (800 1025);
FORCEPROP 1 LAST PATH I120
J 0
(875 1025);
DISPLAY 0.872340 (875 1025);
PAINT AQUA (875 1025);
DISPLAY INVISIBLE (875 1025);
FORCEPROP 1 LAST HDL_POWER GND
J 1
(825 950);
DISPLAY 0.872340 (825 950);
PAINT GREEN (825 950);
DISPLAY INVISIBLE (825 950);
FORCEADD UNIVERSAL_GND..1
(4725 3450);
FORCEPROP 3 LASTPIN (4725 3500) SIG_NAME GND\g
J 0
(4735 3510);
DISPLAY 0.659574 (4735 3510);
PAINT MONO (4735 3510);
DISPLAY INVISIBLE (4735 3510);
FORCEPROP 2 LAST CDS_LIB pure_quanta_power
J 0
(4725 3450);
DISPLAY INVISIBLE (4725 3450);
FORCEPROP 1 LAST PATH I121
J 0
(4800 3450);
DISPLAY 0.872340 (4800 3450);
PAINT AQUA (4800 3450);
DISPLAY INVISIBLE (4800 3450);
FORCEPROP 1 LAST HDL_POWER GND
J 1
(4750 3375);
DISPLAY 0.872340 (4750 3375);
PAINT GREEN (4750 3375);
DISPLAY INVISIBLE (4750 3375);
FORCEADD Q_RES..2
(4725 3675);
FORCEPROP 1 LAST LOCATION PR516
J 0
(4770 3800);
DISPLAY 0.489362 (4770 3800);
PAINT SKYBLUE (4770 3800);
FORCEPROP 0 LAST $SEC 1
J 0
(4775 3850);
DISPLAY 0.680851 (4775 3850);
PAINT MONO (4775 3850);
DISPLAY INVISIBLE (4775 3850);
FORCEPROP 0 LAST CDS_SEC 1
J 0
(4775 3850);
DISPLAY 1.021277 (4775 3850);
DISPLAY INVISIBLE (4775 3850);
FORCEPROP 1 LASTPIN (4725 3775) $PN 1
J 0
(4730 3737);
DISPLAY 0.489362 (4730 3737);
PAINT MONO (4730 3737);
FORCEPROP 1 LASTPIN (4725 3575) $PN 2
J 0
(4730 3585);
DISPLAY 0.489362 (4730 3585);
PAINT MONO (4730 3585);
FORCEPROP 1 LAST WATTAGE 1/8W
J 0
(4765 3650);
DISPLAY 0.489362 (4765 3650);
PAINT SKYBLUE (4765 3650);
FORCEPROP 1 LAST MATERIAL EMPTY
J 0
(4765 3600);
DISPLAY 0.489362 (4765 3600);
PAINT RED (4765 3600);
FORCEPROP 1 LAST TOLERANCE 1%
J 0
(4770 3700);
DISPLAY 0.489362 (4770 3700);
PAINT SKYBLUE (4770 3700);
FORCEPROP 1 LAST VALUE 1.5
J 0
(4770 3750);
DISPLAY 0.489362 (4770 3750);
PAINT SKYBLUE (4770 3750);
FORCEPROP 1 LAST PART_NUMBER CS-1504FB00
J 0
(4765 3550);
DISPLAY 0.489362 (4765 3550);
PAINT SKYBLUE (4765 3550);
FORCEPROP 1 LAST PACK_TYPE 0402LF
J 0
(4765 3500);
DISPLAY 0.489362 (4765 3500);
PAINT SKYBLUE (4765 3500);
FORCEPROP 2 LAST CDS_LIB pure_quanta
J 0
(4725 3675);
DISPLAY INVISIBLE (4725 3675);
FORCEPROP 1 LAST PATH I122
J 0
(4775 3850);
DISPLAY 0.978723 (4775 3850);
PAINT WHITE (4775 3850);
DISPLAY INVISIBLE (4775 3850);
FORCEADD Q_CAP..1
(4725 4225);
FORCEPROP 1 LAST LOCATION PC206
J 0
(4775 4325);
DISPLAY 0.489362 (4775 4325);
PAINT SKYBLUE (4775 4325);
FORCEPROP 0 LAST $SEC 1
J 0
(4775 4375);
DISPLAY 0.680851 (4775 4375);
PAINT MONO (4775 4375);
DISPLAY INVISIBLE (4775 4375);
FORCEPROP 0 LAST CDS_SEC 1
J 0
(4775 4375);
DISPLAY 1.021277 (4775 4375);
DISPLAY INVISIBLE (4775 4375);
FORCEPROP 1 LASTPIN (4725 4325) $PN 1
J 0
(4735 4305);
DISPLAY 0.489362 (4735 4305);
PAINT MONO (4735 4305);
FORCEPROP 1 LASTPIN (4725 4125) $PN 2
J 0
(4735 4105);
DISPLAY 0.489362 (4735 4105);
PAINT MONO (4735 4105);
FORCEPROP 1 LAST MATERIAL EMPTY
J 0
(4775 4125);
DISPLAY 0.489362 (4775 4125);
PAINT RED (4775 4125);
FORCEPROP 1 LAST TOLERANCE 10%
J 0
(4775 4175);
DISPLAY 0.489362 (4775 4175);
PAINT SKYBLUE (4775 4175);
FORCEPROP 1 LAST VALUE 560PF
J 0
(4775 4275);
DISPLAY 0.489362 (4775 4275);
PAINT SKYBLUE (4775 4275);
FORCEPROP 1 LAST PART_NUMBER CH1566K1B09
J 0
(4775 4075);
DISPLAY 0.489362 (4775 4075);
PAINT SKYBLUE (4775 4075);
FORCEPROP 1 LAST VOLTAGE 50V
J 0
(4775 4225);
DISPLAY 0.489362 (4775 4225);
PAINT SKYBLUE (4775 4225);
FORCEPROP 1 LAST PACK_TYPE C0402
J 0
(4775 4025);
DISPLAY 0.489362 (4775 4025);
PAINT SKYBLUE (4775 4025);
FORCEPROP 2 LAST CDS_LIB pure_quanta
J 0
(4725 4225);
DISPLAY INVISIBLE (4725 4225);
FORCEPROP 1 LAST PATH I123
J 0
(4775 4375);
DISPLAY 0.978723 (4775 4375);
PAINT WHITE (4775 4375);
DISPLAY INVISIBLE (4775 4375);
FORCEADD UNIVERSAL_GND..1
(4625 675);
FORCEPROP 3 LASTPIN (4625 725) SIG_NAME GND\g
J 0
(4635 735);
DISPLAY 0.659574 (4635 735);
PAINT MONO (4635 735);
DISPLAY INVISIBLE (4635 735);
FORCEPROP 2 LAST CDS_LIB pure_quanta_power
J 0
(4625 675);
DISPLAY INVISIBLE (4625 675);
FORCEPROP 1 LAST PATH I124
J 0
(4700 675);
DISPLAY 0.872340 (4700 675);
PAINT AQUA (4700 675);
DISPLAY INVISIBLE (4700 675);
FORCEPROP 1 LAST HDL_POWER GND
J 1
(4650 600);
DISPLAY 0.872340 (4650 600);
PAINT GREEN (4650 600);
DISPLAY INVISIBLE (4650 600);
FORCEADD Q_RES..2
(4625 900);
FORCEPROP 1 LAST LOCATION PR515
J 0
(4670 1025);
DISPLAY 0.489362 (4670 1025);
PAINT SKYBLUE (4670 1025);
FORCEPROP 0 LAST $SEC 1
J 0
(4675 1075);
DISPLAY 0.680851 (4675 1075);
PAINT MONO (4675 1075);
DISPLAY INVISIBLE (4675 1075);
FORCEPROP 0 LAST CDS_SEC 1
J 0
(4675 1075);
DISPLAY 1.021277 (4675 1075);
DISPLAY INVISIBLE (4675 1075);
FORCEPROP 1 LASTPIN (4625 1000) $PN 1
J 0
(4630 962);
DISPLAY 0.489362 (4630 962);
PAINT MONO (4630 962);
FORCEPROP 1 LASTPIN (4625 800) $PN 2
J 0
(4630 810);
DISPLAY 0.489362 (4630 810);
PAINT MONO (4630 810);
FORCEPROP 1 LAST WATTAGE 1/8W
J 0
(4665 875);
DISPLAY 0.489362 (4665 875);
PAINT SKYBLUE (4665 875);
FORCEPROP 1 LAST MATERIAL EMPTY
J 0
(4665 825);
DISPLAY 0.489362 (4665 825);
PAINT RED (4665 825);
FORCEPROP 1 LAST TOLERANCE 1%
J 0
(4670 925);
DISPLAY 0.489362 (4670 925);
PAINT SKYBLUE (4670 925);
FORCEPROP 1 LAST VALUE 1.5
J 0
(4670 975);
DISPLAY 0.489362 (4670 975);
PAINT SKYBLUE (4670 975);
FORCEPROP 1 LAST PART_NUMBER CS-1504FB00
J 0
(4665 775);
DISPLAY 0.489362 (4665 775);
PAINT SKYBLUE (4665 775);
FORCEPROP 1 LAST PACK_TYPE 0402LF
J 0
(4665 725);
DISPLAY 0.489362 (4665 725);
PAINT SKYBLUE (4665 725);
FORCEPROP 2 LAST CDS_LIB pure_quanta
J 0
(4625 900);
DISPLAY INVISIBLE (4625 900);
FORCEPROP 1 LAST PATH I125
J 0
(4675 1075);
DISPLAY 0.978723 (4675 1075);
PAINT WHITE (4675 1075);
DISPLAY INVISIBLE (4675 1075);
FORCEADD Q_CAP..1
(4625 1400);
FORCEPROP 1 LAST LOCATION PC205
J 0
(4675 1500);
DISPLAY 0.489362 (4675 1500);
PAINT SKYBLUE (4675 1500);
FORCEPROP 0 LAST $SEC 1
J 0
(4675 1550);
DISPLAY 0.680851 (4675 1550);
PAINT MONO (4675 1550);
DISPLAY INVISIBLE (4675 1550);
FORCEPROP 0 LAST CDS_SEC 1
J 0
(4675 1550);
DISPLAY 1.021277 (4675 1550);
DISPLAY INVISIBLE (4675 1550);
FORCEPROP 1 LASTPIN (4625 1500) $PN 1
J 0
(4635 1480);
DISPLAY 0.489362 (4635 1480);
PAINT MONO (4635 1480);
FORCEPROP 1 LASTPIN (4625 1300) $PN 2
J 0
(4635 1280);
DISPLAY 0.489362 (4635 1280);
PAINT MONO (4635 1280);
FORCEPROP 1 LAST MATERIAL EMPTY
J 0
(4675 1300);
DISPLAY 0.489362 (4675 1300);
PAINT RED (4675 1300);
FORCEPROP 1 LAST TOLERANCE 10%
J 0
(4675 1350);
DISPLAY 0.489362 (4675 1350);
PAINT SKYBLUE (4675 1350);
FORCEPROP 1 LAST VALUE 560PF
J 0
(4675 1450);
DISPLAY 0.489362 (4675 1450);
PAINT SKYBLUE (4675 1450);
FORCEPROP 1 LAST PART_NUMBER CH1566K1B09
J 0
(4675 1250);
DISPLAY 0.489362 (4675 1250);
PAINT SKYBLUE (4675 1250);
FORCEPROP 1 LAST VOLTAGE 50V
J 0
(4675 1400);
DISPLAY 0.489362 (4675 1400);
PAINT SKYBLUE (4675 1400);
FORCEPROP 1 LAST PACK_TYPE C0402
J 0
(4675 1200);
DISPLAY 0.489362 (4675 1200);
PAINT SKYBLUE (4675 1200);
FORCEPROP 2 LAST CDS_LIB pure_quanta
J 0
(4625 1400);
DISPLAY INVISIBLE (4625 1400);
FORCEPROP 1 LAST PATH I126
J 0
(4675 1550);
DISPLAY 0.978723 (4675 1550);
PAINT WHITE (4675 1550);
DISPLAY INVISIBLE (4675 1550);
FORCEADD UNIVERSAL_GND..1
(7475 1250);
FORCEPROP 3 LASTPIN (7475 1300) SIG_NAME GND\g
J 0
(7485 1310);
DISPLAY 0.659574 (7485 1310);
PAINT MONO (7485 1310);
DISPLAY INVISIBLE (7485 1310);
FORCEPROP 2 LAST CDS_LIB pure_quanta_power
J 0
(7475 1250);
DISPLAY INVISIBLE (7475 1250);
FORCEPROP 1 LAST PATH I127
J 0
(7550 1250);
DISPLAY 0.872340 (7550 1250);
PAINT AQUA (7550 1250);
DISPLAY INVISIBLE (7550 1250);
FORCEPROP 1 LAST HDL_POWER GND
J 1
(7500 1175);
DISPLAY 0.872340 (7500 1175);
PAINT GREEN (7500 1175);
DISPLAY INVISIBLE (7500 1175);
FORCEADD VCC_CORE..1
(1625 5825);
FORCEPROP 3 LASTPIN (1625 5775) SIG_NAME PVDDCR_CPU1_P1_PVCC\g
J 0
(1635 5785);
DISPLAY 0.659574 (1635 5785);
PAINT MONO (1635 5785);
DISPLAY INVISIBLE (1635 5785);
FORCEPROP 1 LAST HDL_POWER PVDDCR_CPU1_P1_PVCC
J 1
(1625 5875);
DISPLAY 0.489362 (1625 5875);
PAINT GREEN (1625 5875);
FORCEPROP 2 LAST CDS_LIB pure_quanta_power
J 0
(1625 5825);
DISPLAY INVISIBLE (1625 5825);
FORCEPROP 1 LAST PATH I128
J 0
(1675 5850);
DISPLAY 0.872340 (1675 5850);
PAINT AQUA (1675 5850);
DISPLAY INVISIBLE (1675 5850);
FORCEADD VCC_CORE..1
(1450 3000);
FORCEPROP 3 LASTPIN (1450 2950) SIG_NAME PVDDCR_CPU1_P1_PVCC\g
J 0
(1460 2960);
DISPLAY 0.659574 (1460 2960);
PAINT MONO (1460 2960);
DISPLAY INVISIBLE (1460 2960);
FORCEPROP 1 LAST HDL_POWER PVDDCR_CPU1_P1_PVCC
J 1
(1450 3050);
DISPLAY 0.489362 (1450 3050);
PAINT GREEN (1450 3050);
FORCEPROP 2 LAST CDS_LIB pure_quanta_power
J 0
(1450 3000);
DISPLAY INVISIBLE (1450 3000);
FORCEPROP 1 LAST PATH I129
J 0
(1500 3025);
DISPLAY 0.872340 (1500 3025);
PAINT AQUA (1500 3025);
DISPLAY INVISIBLE (1500 3025);
FORCEADD ISL99390FRZTR5935..1
(3225 1600);
FORCEPROP 1 LAST LOCATION PU36
J 0
(2925 2475);
DISPLAY 0.489362 (2925 2475);
PAINT SKYBLUE (2925 2475);
FORCEPROP 2 LAST $SEC 1
J 0
(2925 2525);
DISPLAY 0.680851 (2925 2525);
PAINT MONO (2925 2525);
DISPLAY INVISIBLE (2925 2525);
FORCEPROP 2 LAST CDS_SEC 1
J 0
(2925 2525);
DISPLAY 1.021277 (2925 2525);
DISPLAY INVISIBLE (2925 2525);
FORCEPROP 2 LASTPIN (3625 1150) $PN 2
J 0
(3635 1160);
DISPLAY 0.489362 (3635 1160);
PAINT MONO (3635 1160);
FORCEPROP 2 LASTPIN (3625 1950) $PN 33
J 0
(3635 1960);
DISPLAY 0.489362 (3635 1960);
PAINT MONO (3635 1960);
FORCEPROP 2 LASTPIN (2775 1350) $PN 31
J 2
(2765 1360);
DISPLAY 0.489362 (2765 1360);
PAINT MONO (2765 1360);
FORCEPROP 2 LASTPIN (2775 1750) $PN 35
J 2
(2765 1760);
DISPLAY 0.489362 (2765 1760);
PAINT MONO (2765 1760);
FORCEPROP 2 LASTPIN (3625 1300) $PN 6
J 0
(3635 1310);
DISPLAY 0.489362 (3635 1310);
PAINT MONO (3635 1310);
FORCEPROP 2 LASTPIN (3625 1250) $PN 41
J 0
(3635 1260);
DISPLAY 0.489362 (3635 1260);
PAINT MONO (3635 1260);
FORCEPROP 2 LASTPIN (2775 1600) $PN 38
J 2
(2765 1610);
DISPLAY 0.489362 (2765 1610);
PAINT MONO (2765 1610);
FORCEPROP 2 LASTPIN (2775 1300) $PN 37
J 2
(2765 1310);
DISPLAY 0.489362 (2765 1310);
PAINT MONO (2765 1310);
FORCEPROP 2 LASTPIN (3625 1100) $PN 5
J 0
(3635 1110);
DISPLAY 0.489362 (3635 1110);
PAINT MONO (3635 1110);
FORCEPROP 2 LASTPIN (3625 1050) $PN 7_9-20_24
J 0
(3635 1060);
DISPLAY 0.489362 (3635 1060);
PAINT MONO (3635 1060);
FORCEPROP 2 LASTPIN (3625 1000) $PN 40
J 0
(3635 1010);
DISPLAY 0.489362 (3635 1010);
PAINT MONO (3635 1010);
FORCEPROP 2 LASTPIN (3625 1700) $PN 32
J 0
(3635 1710);
DISPLAY 0.489362 (3635 1710);
PAINT MONO (3635 1710);
FORCEPROP 2 LASTPIN (2775 2250) $PN 4
J 2
(2765 2260);
DISPLAY 0.489362 (2765 2260);
PAINT MONO (2765 2260);
FORCEPROP 2 LASTPIN (2775 1000) $PN 34
J 2
(2765 1010);
DISPLAY 0.489362 (2765 1010);
PAINT MONO (2765 1010);
FORCEPROP 2 LASTPIN (2775 1500) $PN 39
J 2
(2765 1510);
DISPLAY 0.489362 (2765 1510);
PAINT MONO (2765 1510);
FORCEPROP 2 LASTPIN (3625 1600) $PN 10_19
J 0
(3635 1610);
DISPLAY 0.489362 (3635 1610);
PAINT MONO (3635 1610);
FORCEPROP 2 LASTPIN (2775 1100) $PN 36
J 2
(2765 1110);
DISPLAY 0.489362 (2765 1110);
PAINT MONO (2765 1110);
FORCEPROP 2 LASTPIN (2775 1950) $PN 3
J 2
(2765 1960);
DISPLAY 0.489362 (2765 1960);
PAINT MONO (2765 1960);
FORCEPROP 2 LASTPIN (3625 2250) $PN 25_29
J 0
(3635 2260);
DISPLAY 0.489362 (3635 2260);
PAINT MONO (3635 2260);
FORCEPROP 2 LASTPIN (3625 2200) $PN 30
J 0
(3635 2210);
DISPLAY 0.489362 (3635 2210);
PAINT MONO (3635 2210);
FORCEPROP 2 LASTPIN (3625 1350) $PN 1
J 0
(3635 1360);
DISPLAY 0.489362 (3635 1360);
PAINT MONO (3635 1360);
FORCEPROP 2 LAST PART_TYPE SMLF
J 0
(2925 2625);
DISPLAY 0.638298 (2925 2625);
FORCEPROP 1 LAST MATERIAL IC
J 0
(2925 2325);
DISPLAY 0.489362 (2925 2325);
PAINT SKYBLUE (2925 2325);
FORCEPROP 2 LAST VALUE ISL99390FRZ-TR5935
J 0
(2925 2575);
DISPLAY 0.489362 (2925 2575);
PAINT SKYBLUE (2925 2575);
FORCEPROP 1 LAST PART_NUMBER AL099390004
J 0
(2925 2400);
DISPLAY 0.489362 (2925 2400);
PAINT SKYBLUE (2925 2400);
FORCEPROP 2 LAST CDS_LIB pure_quanta
J 0
(3225 1600);
DISPLAY INVISIBLE (3225 1600);
FORCEPROP 1 LAST CDS_LMAN_SYM_OUTLINE -300,700,250,-650
J 0
(3225 1600);
DISPLAY 0.468085 (3225 1600);
PAINT GREEN (3225 1600);
DISPLAY INVISIBLE (3225 1600);
FORCEPROP 1 LAST NEEDS_NO_SIZE TRUE
J 0
(3225 1600);
DISPLAY 0.723404 (3225 1600);
PAINT GREEN (3225 1600);
DISPLAY INVISIBLE (3225 1600);
FORCEPROP 1 LAST PATH I14
J 0
(3225 1600);
DISPLAY 0.723404 (3225 1600);
PAINT GREEN (3225 1600);
DISPLAY INVISIBLE (3225 1600);
FORCEADD UNIVERSAL_GND..1
(3875 875);
FORCEPROP 3 LASTPIN (3875 925) SIG_NAME GND\g
J 0
(3885 935);
DISPLAY 0.659574 (3885 935);
PAINT MONO (3885 935);
DISPLAY INVISIBLE (3885 935);
FORCEPROP 2 LAST CDS_LIB pure_quanta_power
J 0
(3875 875);
PAINT MONO (3875 875);
DISPLAY INVISIBLE (3875 875);
FORCEPROP 1 LAST PATH I15
J 0
(3950 875);
DISPLAY 0.872340 (3950 875);
PAINT AQUA (3950 875);
DISPLAY INVISIBLE (3950 875);
FORCEPROP 1 LAST HDL_POWER GND
J 1
(3900 800);
DISPLAY 0.872340 (3900 800);
PAINT GREEN (3900 800);
DISPLAY INVISIBLE (3900 800);
FORCEADD UNIVERSAL_GND..1
(3900 3700);
FORCEPROP 3 LASTPIN (3900 3750) SIG_NAME GND\g
J 0
(3910 3760);
DISPLAY 0.659574 (3910 3760);
PAINT MONO (3910 3760);
DISPLAY INVISIBLE (3910 3760);
FORCEPROP 2 LAST CDS_LIB pure_quanta_power
J 0
(3900 3700);
PAINT MONO (3900 3700);
DISPLAY INVISIBLE (3900 3700);
FORCEPROP 1 LAST PATH I18
J 0
(3975 3700);
DISPLAY 0.872340 (3975 3700);
PAINT AQUA (3975 3700);
DISPLAY INVISIBLE (3975 3700);
FORCEPROP 1 LAST HDL_POWER GND
J 1
(3925 3625);
DISPLAY 0.872340 (3925 3625);
PAINT GREEN (3925 3625);
DISPLAY INVISIBLE (3925 3625);
FORCEADD Q_RES..2
R 2
(1325 3925);
FORCEPROP 1 LAST LOCATION PR263
J 2
(1280 4050);
DISPLAY 0.489362 (1280 4050);
PAINT SKYBLUE (1280 4050);
FORCEPROP 0 LAST $SEC 1
J 0
(1300 4100);
DISPLAY 0.680851 (1300 4100);
PAINT MONO (1300 4100);
DISPLAY INVISIBLE (1300 4100);
FORCEPROP 0 LAST CDS_SEC 1
J 0
(1300 4100);
DISPLAY 1.021277 (1300 4100);
DISPLAY INVISIBLE (1300 4100);
FORCEPROP 1 LASTPIN (1325 4025) $PN 1
J 2
(1320 3987);
DISPLAY 0.489362 (1320 3987);
PAINT MONO (1320 3987);
FORCEPROP 1 LASTPIN (1325 3825) $PN 2
J 2
(1320 3835);
DISPLAY 0.489362 (1320 3835);
PAINT MONO (1320 3835);
FORCEPROP 1 LAST WATTAGE 1/16W
J 2
(1285 3900);
DISPLAY 0.489362 (1285 3900);
PAINT SKYBLUE (1285 3900);
FORCEPROP 1 LAST MATERIAL EMPTY
J 2
(1285 3850);
DISPLAY 0.489362 (1285 3850);
PAINT RED (1285 3850);
FORCEPROP 1 LAST TOLERANCE 1%
J 2
(1280 3950);
DISPLAY 0.489362 (1280 3950);
PAINT SKYBLUE (1280 3950);
FORCEPROP 1 LAST VALUE 8.87K
J 2
(1280 4000);
DISPLAY 0.489362 (1280 4000);
PAINT SKYBLUE (1280 4000);
FORCEPROP 1 LAST PART_NUMBER CS28872FB01
J 2
(1285 3800);
DISPLAY 0.489362 (1285 3800);
PAINT SKYBLUE (1285 3800);
FORCEPROP 1 LAST PACK_TYPE 0402LF
J 2
(1285 3750);
DISPLAY 0.489362 (1285 3750);
PAINT SKYBLUE (1285 3750);
FORCEPROP 2 LAST CDS_LIB pure_quanta
J 2
(1325 3925);
DISPLAY INVISIBLE (1325 3925);
FORCEPROP 1 LAST PATH I19
J 2
(1275 4100);
DISPLAY 0.978723 (1275 4100);
PAINT WHITE (1275 4100);
DISPLAY INVISIBLE (1275 4100);
FORCEADD Q_RES..2
R 2
(1300 1100);
FORCEPROP 1 LAST LOCATION PR262
J 2
(1255 1225);
DISPLAY 0.489362 (1255 1225);
PAINT SKYBLUE (1255 1225);
FORCEPROP 0 LAST $SEC 1
J 0
(1275 1275);
DISPLAY 0.680851 (1275 1275);
PAINT MONO (1275 1275);
DISPLAY INVISIBLE (1275 1275);
FORCEPROP 0 LAST CDS_SEC 1
J 0
(1275 1275);
DISPLAY 1.021277 (1275 1275);
DISPLAY INVISIBLE (1275 1275);
FORCEPROP 1 LASTPIN (1300 1200) $PN 1
J 2
(1295 1162);
DISPLAY 0.489362 (1295 1162);
PAINT MONO (1295 1162);
FORCEPROP 1 LASTPIN (1300 1000) $PN 2
J 2
(1295 1010);
DISPLAY 0.489362 (1295 1010);
PAINT MONO (1295 1010);
FORCEPROP 1 LAST WATTAGE 1/16W
J 2
(1260 1075);
DISPLAY 0.489362 (1260 1075);
PAINT SKYBLUE (1260 1075);
FORCEPROP 1 LAST MATERIAL EMPTY
J 2
(1260 1025);
DISPLAY 0.489362 (1260 1025);
PAINT RED (1260 1025);
FORCEPROP 1 LAST TOLERANCE 1%
J 2
(1255 1125);
DISPLAY 0.489362 (1255 1125);
PAINT SKYBLUE (1255 1125);
FORCEPROP 1 LAST VALUE 8.87K
J 2
(1255 1175);
DISPLAY 0.489362 (1255 1175);
PAINT SKYBLUE (1255 1175);
FORCEPROP 1 LAST PART_NUMBER CS28872FB01
J 2
(1260 975);
DISPLAY 0.489362 (1260 975);
PAINT SKYBLUE (1260 975);
FORCEPROP 1 LAST PACK_TYPE 0402LF
J 2
(1260 925);
DISPLAY 0.489362 (1260 925);
PAINT SKYBLUE (1260 925);
FORCEPROP 2 LAST CDS_LIB pure_quanta
J 2
(1300 1100);
DISPLAY INVISIBLE (1300 1100);
FORCEPROP 1 LAST PATH I2
J 2
(1250 1275);
DISPLAY 0.978723 (1250 1275);
PAINT WHITE (1250 1275);
DISPLAY INVISIBLE (1250 1275);
FORCEADD OFFPAGE..1
(1800 3825);
FORCEPROP 2 LAST $XR0 193 
J 0
(1374 3825);
DISPLAY 0.638298 (1374 3825);
PAINT MONO (1374 3825);
FORCEPROP 2 LAST PATH I21
J 0
(1375 3875);
DISPLAY 1.021277 (1375 3875);
DISPLAY INVISIBLE (1375 3875);
FORCEPROP 1 LAST COMMENT_BODY TRUE
J 0
(1925 3725);
DISPLAY 0.872340 (1925 3725);
PAINT GREEN (1925 3725);
DISPLAY INVISIBLE (1925 3725);
FORCEPROP 1 LAST OFFPAGE TRUE
J 0
(2125 3700);
DISPLAY 0.872340 (2125 3700);
PAINT GREEN (2125 3700);
DISPLAY INVISIBLE (2125 3700);
FORCEPROP 2 LAST CDS_LIB standard
J 0
(1800 3825);
DISPLAY INVISIBLE (1800 3825);
FORCEADD OFFPAGE..5
(1800 3925);
FORCEPROP 2 LAST $XR3 193 
J 0
(1545 3853);
DISPLAY 0.638298 (1545 3853);
PAINT MONO (1545 3853);
FORCEPROP 2 LAST $XR2 196 
J 0
(1545 3961);
DISPLAY 0.638298 (1545 3961);
PAINT MONO (1545 3961);
FORCEPROP 2 LAST $XR1 195 
J 0
(1545 3889);
DISPLAY 0.638298 (1545 3889);
PAINT MONO (1545 3889);
FORCEPROP 2 LAST $XR0 194 
J 0
(1545 3925);
DISPLAY 0.638298 (1545 3925);
PAINT MONO (1545 3925);
FORCEPROP 2 LAST PATH I22
J 0
(1550 4075);
DISPLAY 1.021277 (1550 4075);
DISPLAY INVISIBLE (1550 4075);
FORCEPROP 1 LAST COMMENT_BODY TRUE
J 0
(1900 3850);
DISPLAY 0.872340 (1900 3850);
PAINT GREEN (1900 3850);
DISPLAY INVISIBLE (1900 3850);
FORCEPROP 1 LAST OFFPAGE TRUE
J 0
(2125 3800);
DISPLAY 0.872340 (2125 3800);
PAINT GREEN (2125 3800);
DISPLAY INVISIBLE (2125 3800);
FORCEPROP 2 LAST CDS_LIB standard
J 0
(1800 3925);
DISPLAY INVISIBLE (1800 3925);
FORCEADD OFFPAGE..1
(1800 4325);
FORCEPROP 2 LAST $XR5 199 
J 0
(918 4325);
DISPLAY 0.638298 (918 4325);
PAINT MONO (918 4325);
FORCEPROP 2 LAST $XR4 198 
J 0
(1038 4325);
DISPLAY 0.638298 (1038 4325);
PAINT MONO (1038 4325);
FORCEPROP 2 LAST $XR3 196 
J 0
(1158 4325);
DISPLAY 0.638298 (1158 4325);
PAINT MONO (1158 4325);
FORCEPROP 2 LAST $XR2 195 
J 0
(1278 4325);
DISPLAY 0.638298 (1278 4325);
PAINT MONO (1278 4325);
FORCEPROP 2 LAST $XR1 194 
J 0
(1398 4325);
DISPLAY 0.638298 (1398 4325);
PAINT MONO (1398 4325);
FORCEPROP 2 LAST $XR0 193 
J 0
(1518 4325);
DISPLAY 0.638298 (1518 4325);
PAINT MONO (1518 4325);
FORCEPROP 2 LAST PATH I23
J 0
(1525 4375);
DISPLAY 1.021277 (1525 4375);
DISPLAY INVISIBLE (1525 4375);
FORCEPROP 1 LAST COMMENT_BODY TRUE
J 0
(1925 4225);
DISPLAY 0.872340 (1925 4225);
PAINT GREEN (1925 4225);
DISPLAY INVISIBLE (1925 4225);
FORCEPROP 1 LAST OFFPAGE TRUE
J 0
(2125 4200);
DISPLAY 0.872340 (2125 4200);
PAINT GREEN (2125 4200);
DISPLAY INVISIBLE (2125 4200);
FORCEPROP 2 LAST CDS_LIB standard
J 0
(1800 4325);
DISPLAY INVISIBLE (1800 4325);
FORCEADD OFFPAGE..5
(1800 4425);
FORCEPROP 2 LAST $XR0 193 
J 0
(1545 4425);
DISPLAY 0.638298 (1545 4425);
PAINT MONO (1545 4425);
FORCEPROP 2 LAST PATH I24
J 0
(1550 4475);
DISPLAY 1.021277 (1550 4475);
DISPLAY INVISIBLE (1550 4475);
FORCEPROP 1 LAST COMMENT_BODY TRUE
J 0
(1900 4350);
DISPLAY 0.872340 (1900 4350);
PAINT GREEN (1900 4350);
DISPLAY INVISIBLE (1900 4350);
FORCEPROP 1 LAST OFFPAGE TRUE
J 0
(2125 4300);
DISPLAY 0.872340 (2125 4300);
PAINT GREEN (2125 4300);
DISPLAY INVISIBLE (2125 4300);
FORCEPROP 2 LAST CDS_LIB standard
J 0
(1800 4425);
DISPLAY INVISIBLE (1800 4425);
FORCEADD ISL99390FRZTR5935..1
(3250 4425);
FORCEPROP 1 LAST LOCATION PU37
J 0
(2950 5300);
DISPLAY 0.489362 (2950 5300);
PAINT SKYBLUE (2950 5300);
FORCEPROP 2 LAST $SEC 1
J 0
(2950 5350);
DISPLAY 0.680851 (2950 5350);
PAINT MONO (2950 5350);
DISPLAY INVISIBLE (2950 5350);
FORCEPROP 2 LAST CDS_SEC 1
J 0
(2950 5350);
DISPLAY 1.021277 (2950 5350);
DISPLAY INVISIBLE (2950 5350);
FORCEPROP 2 LASTPIN (3650 3975) $PN 2
J 0
(3660 3985);
DISPLAY 0.489362 (3660 3985);
PAINT MONO (3660 3985);
FORCEPROP 2 LASTPIN (3650 4775) $PN 33
J 0
(3660 4785);
DISPLAY 0.489362 (3660 4785);
PAINT MONO (3660 4785);
FORCEPROP 2 LASTPIN (2800 4175) $PN 31
J 2
(2790 4185);
DISPLAY 0.489362 (2790 4185);
PAINT MONO (2790 4185);
FORCEPROP 2 LASTPIN (2800 4575) $PN 35
J 2
(2790 4585);
DISPLAY 0.489362 (2790 4585);
PAINT MONO (2790 4585);
FORCEPROP 2 LASTPIN (3650 4125) $PN 6
J 0
(3660 4135);
DISPLAY 0.489362 (3660 4135);
PAINT MONO (3660 4135);
FORCEPROP 2 LASTPIN (3650 4075) $PN 41
J 0
(3660 4085);
DISPLAY 0.489362 (3660 4085);
PAINT MONO (3660 4085);
FORCEPROP 2 LASTPIN (2800 4425) $PN 38
J 2
(2790 4435);
DISPLAY 0.489362 (2790 4435);
PAINT MONO (2790 4435);
FORCEPROP 2 LASTPIN (2800 4125) $PN 37
J 2
(2790 4135);
DISPLAY 0.489362 (2790 4135);
PAINT MONO (2790 4135);
FORCEPROP 2 LASTPIN (3650 3925) $PN 5
J 0
(3660 3935);
DISPLAY 0.489362 (3660 3935);
PAINT MONO (3660 3935);
FORCEPROP 2 LASTPIN (3650 3875) $PN 7_9-20_24
J 0
(3660 3885);
DISPLAY 0.489362 (3660 3885);
PAINT MONO (3660 3885);
FORCEPROP 2 LASTPIN (3650 3825) $PN 40
J 0
(3660 3835);
DISPLAY 0.489362 (3660 3835);
PAINT MONO (3660 3835);
FORCEPROP 2 LASTPIN (3650 4525) $PN 32
J 0
(3660 4535);
DISPLAY 0.489362 (3660 4535);
PAINT MONO (3660 4535);
FORCEPROP 2 LASTPIN (2800 5075) $PN 4
J 2
(2790 5085);
DISPLAY 0.489362 (2790 5085);
PAINT MONO (2790 5085);
FORCEPROP 2 LASTPIN (2800 3825) $PN 34
J 2
(2790 3835);
DISPLAY 0.489362 (2790 3835);
PAINT MONO (2790 3835);
FORCEPROP 2 LASTPIN (2800 4325) $PN 39
J 2
(2790 4335);
DISPLAY 0.489362 (2790 4335);
PAINT MONO (2790 4335);
FORCEPROP 2 LASTPIN (3650 4425) $PN 10_19
J 0
(3660 4435);
DISPLAY 0.489362 (3660 4435);
PAINT MONO (3660 4435);
FORCEPROP 2 LASTPIN (2800 3925) $PN 36
J 2
(2790 3935);
DISPLAY 0.489362 (2790 3935);
PAINT MONO (2790 3935);
FORCEPROP 2 LASTPIN (2800 4775) $PN 3
J 2
(2790 4785);
DISPLAY 0.489362 (2790 4785);
PAINT MONO (2790 4785);
FORCEPROP 2 LASTPIN (3650 5075) $PN 25_29
J 0
(3660 5085);
DISPLAY 0.489362 (3660 5085);
PAINT MONO (3660 5085);
FORCEPROP 2 LASTPIN (3650 5025) $PN 30
J 0
(3660 5035);
DISPLAY 0.489362 (3660 5035);
PAINT MONO (3660 5035);
FORCEPROP 2 LASTPIN (3650 4175) $PN 1
J 0
(3660 4185);
DISPLAY 0.489362 (3660 4185);
PAINT MONO (3660 4185);
FORCEPROP 2 LAST PART_TYPE SMLF
J 0
(2950 5450);
DISPLAY 0.638298 (2950 5450);
FORCEPROP 1 LAST MATERIAL IC
J 0
(2950 5150);
DISPLAY 0.489362 (2950 5150);
PAINT SKYBLUE (2950 5150);
FORCEPROP 2 LAST VALUE ISL99390FRZ-TR5935
J 0
(2950 5400);
DISPLAY 0.489362 (2950 5400);
PAINT SKYBLUE (2950 5400);
FORCEPROP 1 LAST PART_NUMBER AL099390004
J 0
(2950 5225);
DISPLAY 0.489362 (2950 5225);
PAINT SKYBLUE (2950 5225);
FORCEPROP 2 LAST CDS_LIB pure_quanta
J 0
(3250 4425);
DISPLAY INVISIBLE (3250 4425);
FORCEPROP 1 LAST CDS_LMAN_SYM_OUTLINE -300,700,250,-650
J 0
(3250 4425);
DISPLAY 0.468085 (3250 4425);
PAINT GREEN (3250 4425);
DISPLAY INVISIBLE (3250 4425);
FORCEPROP 1 LAST NEEDS_NO_SIZE TRUE
J 0
(3250 4425);
DISPLAY 0.723404 (3250 4425);
PAINT GREEN (3250 4425);
DISPLAY INVISIBLE (3250 4425);
FORCEPROP 1 LAST PATH I30
J 0
(3250 4425);
DISPLAY 0.723404 (3250 4425);
PAINT GREEN (3250 4425);
DISPLAY INVISIBLE (3250 4425);
FORCEADD Q_CAP..1
(4425 2500);
FORCEPROP 1 LAST LOCATION PC407_4
J 0
(4475 2650);
DISPLAY 0.489362 (4475 2650);
PAINT SKYBLUE (4475 2650);
FORCEPROP 0 LAST $SEC 1
J 0
(4475 2700);
DISPLAY 0.680851 (4475 2700);
PAINT MONO (4475 2700);
DISPLAY INVISIBLE (4475 2700);
FORCEPROP 0 LAST CDS_SEC 1
J 0
(4475 2700);
DISPLAY 1.021277 (4475 2700);
DISPLAY INVISIBLE (4475 2700);
FORCEPROP 1 LASTPIN (4425 2600) $PN 1
J 0
(4435 2580);
DISPLAY 0.489362 (4435 2580);
PAINT MONO (4435 2580);
FORCEPROP 1 LASTPIN (4425 2400) $PN 2
J 0
(4435 2380);
DISPLAY 0.489362 (4435 2380);
PAINT MONO (4435 2380);
FORCEPROP 1 LAST MATERIAL X6S
J 0
(4475 2450);
DISPLAY 0.489362 (4475 2450);
PAINT SKYBLUE (4475 2450);
FORCEPROP 1 LAST TOLERANCE 10%
J 0
(4475 2500);
DISPLAY 0.489362 (4475 2500);
PAINT SKYBLUE (4475 2500);
FORCEPROP 1 LAST VALUE 1UF
J 0
(4475 2600);
DISPLAY 0.489362 (4475 2600);
PAINT SKYBLUE (4475 2600);
FORCEPROP 1 LAST PART_NUMBER CH5104KEB02
J 0
(4475 2350);
DISPLAY 0.489362 (4475 2350);
PAINT SKYBLUE (4475 2350);
FORCEPROP 1 LAST VOLTAGE 25V
J 0
(4475 2550);
DISPLAY 0.489362 (4475 2550);
PAINT SKYBLUE (4475 2550);
FORCEPROP 1 LAST PACK_TYPE C0402
J 0
(4475 2400);
DISPLAY 0.489362 (4475 2400);
PAINT SKYBLUE (4475 2400);
FORCEPROP 2 LAST CDS_LIB pure_quanta
J 0
(4425 2500);
DISPLAY INVISIBLE (4425 2500);
FORCEPROP 1 LAST PATH I37
J 0
(4475 2650);
DISPLAY 0.978723 (4475 2650);
PAINT WHITE (4475 2650);
DISPLAY INVISIBLE (4475 2650);
FORCEADD Q_CAP..1
(4825 2500);
FORCEPROP 1 LAST LOCATION PC409_4
J 0
(4875 2650);
DISPLAY 0.489362 (4875 2650);
PAINT SKYBLUE (4875 2650);
FORCEPROP 0 LAST $SEC 1
J 0
(4875 2700);
DISPLAY 0.680851 (4875 2700);
PAINT MONO (4875 2700);
DISPLAY INVISIBLE (4875 2700);
FORCEPROP 0 LAST CDS_SEC 1
J 0
(4875 2700);
DISPLAY 1.021277 (4875 2700);
DISPLAY INVISIBLE (4875 2700);
FORCEPROP 1 LASTPIN (4825 2600) $PN 1
J 0
(4835 2580);
DISPLAY 0.489362 (4835 2580);
PAINT MONO (4835 2580);
FORCEPROP 1 LASTPIN (4825 2400) $PN 2
J 0
(4835 2380);
DISPLAY 0.489362 (4835 2380);
PAINT MONO (4835 2380);
FORCEPROP 1 LAST MATERIAL X6S
J 0
(4875 2450);
DISPLAY 0.489362 (4875 2450);
PAINT SKYBLUE (4875 2450);
FORCEPROP 1 LAST TOLERANCE 10%
J 0
(4875 2500);
DISPLAY 0.489362 (4875 2500);
PAINT SKYBLUE (4875 2500);
FORCEPROP 1 LAST VALUE 10UF
J 0
(4875 2600);
DISPLAY 0.489362 (4875 2600);
PAINT SKYBLUE (4875 2600);
FORCEPROP 1 LAST PART_NUMBER CH6104KEA00
J 0
(4875 2350);
DISPLAY 0.489362 (4875 2350);
PAINT SKYBLUE (4875 2350);
FORCEPROP 1 LAST VOLTAGE 25V
J 0
(4875 2550);
DISPLAY 0.489362 (4875 2550);
PAINT SKYBLUE (4875 2550);
FORCEPROP 1 LAST PACK_TYPE C0805
J 0
(4875 2400);
DISPLAY 0.489362 (4875 2400);
PAINT SKYBLUE (4875 2400);
FORCEPROP 2 LAST CDS_LIB pure_quanta
J 0
(4825 2500);
DISPLAY INVISIBLE (4825 2500);
FORCEPROP 1 LAST PATH I38
J 0
(4875 2650);
DISPLAY 0.978723 (4875 2650);
PAINT WHITE (4875 2650);
DISPLAY INVISIBLE (4875 2650);
FORCEADD OFFPAGE..5
(1775 1100);
FORCEPROP 2 LAST $XR3 193 
J 0
(1520 1172);
DISPLAY 0.638298 (1520 1172);
PAINT MONO (1520 1172);
FORCEPROP 2 LAST $XR2 196 
J 0
(1520 1136);
DISPLAY 0.638298 (1520 1136);
PAINT MONO (1520 1136);
FORCEPROP 2 LAST $XR1 195 
J 0
(1520 1064);
DISPLAY 0.638298 (1520 1064);
PAINT MONO (1520 1064);
FORCEPROP 2 LAST $XR0 194 
J 0
(1520 1100);
DISPLAY 0.638298 (1520 1100);
PAINT MONO (1520 1100);
FORCEPROP 2 LAST PATH I4
J 0
(1500 1250);
DISPLAY 1.021277 (1500 1250);
DISPLAY INVISIBLE (1500 1250);
FORCEPROP 1 LAST COMMENT_BODY TRUE
J 0
(1875 1025);
DISPLAY 0.872340 (1875 1025);
PAINT GREEN (1875 1025);
DISPLAY INVISIBLE (1875 1025);
FORCEPROP 1 LAST OFFPAGE TRUE
J 0
(2100 975);
DISPLAY 0.872340 (2100 975);
PAINT GREEN (2100 975);
DISPLAY INVISIBLE (2100 975);
FORCEPROP 2 LAST CDS_LIB standard
J 0
(1775 1100);
DISPLAY INVISIBLE (1775 1100);
FORCEADD Q_CAP..1
(5225 2500);
FORCEPROP 1 LAST LOCATION PC411_4
J 0
(5275 2650);
DISPLAY 0.489362 (5275 2650);
PAINT SKYBLUE (5275 2650);
FORCEPROP 0 LAST $SEC 1
J 0
(5275 2700);
DISPLAY 0.680851 (5275 2700);
PAINT MONO (5275 2700);
DISPLAY INVISIBLE (5275 2700);
FORCEPROP 0 LAST CDS_SEC 1
J 0
(5275 2700);
DISPLAY 1.021277 (5275 2700);
DISPLAY INVISIBLE (5275 2700);
FORCEPROP 1 LASTPIN (5225 2600) $PN 1
J 0
(5235 2580);
DISPLAY 0.489362 (5235 2580);
PAINT MONO (5235 2580);
FORCEPROP 1 LASTPIN (5225 2400) $PN 2
J 0
(5235 2380);
DISPLAY 0.489362 (5235 2380);
PAINT MONO (5235 2380);
FORCEPROP 1 LAST MATERIAL X6S
J 0
(5275 2450);
DISPLAY 0.489362 (5275 2450);
PAINT SKYBLUE (5275 2450);
FORCEPROP 1 LAST TOLERANCE 10%
J 0
(5275 2500);
DISPLAY 0.489362 (5275 2500);
PAINT SKYBLUE (5275 2500);
FORCEPROP 1 LAST VALUE 10UF
J 0
(5275 2600);
DISPLAY 0.489362 (5275 2600);
PAINT SKYBLUE (5275 2600);
FORCEPROP 1 LAST PART_NUMBER CH6104KEA00
J 0
(5275 2350);
DISPLAY 0.489362 (5275 2350);
PAINT SKYBLUE (5275 2350);
FORCEPROP 1 LAST VOLTAGE 25V
J 0
(5275 2550);
DISPLAY 0.489362 (5275 2550);
PAINT SKYBLUE (5275 2550);
FORCEPROP 1 LAST PACK_TYPE C0805
J 0
(5275 2400);
DISPLAY 0.489362 (5275 2400);
PAINT SKYBLUE (5275 2400);
FORCEPROP 2 LAST CDS_LIB pure_quanta
J 0
(5225 2500);
DISPLAY INVISIBLE (5225 2500);
FORCEPROP 1 LAST PATH I40
J 0
(5275 2650);
DISPLAY 0.978723 (5275 2650);
PAINT WHITE (5275 2650);
DISPLAY INVISIBLE (5275 2650);
FORCEADD UNIVERSAL_GND..1
(5600 2125);
FORCEPROP 3 LASTPIN (5600 2175) SIG_NAME GND\g
J 0
(5610 2185);
DISPLAY 0.659574 (5610 2185);
PAINT MONO (5610 2185);
DISPLAY INVISIBLE (5610 2185);
FORCEPROP 2 LAST CDS_LIB pure_quanta_power
J 0
(5600 2125);
PAINT MONO (5600 2125);
DISPLAY INVISIBLE (5600 2125);
FORCEPROP 1 LAST PATH I41
J 0
(5675 2125);
DISPLAY 0.872340 (5675 2125);
PAINT AQUA (5675 2125);
DISPLAY INVISIBLE (5675 2125);
FORCEPROP 1 LAST HDL_POWER GND
J 1
(5625 2050);
DISPLAY 0.872340 (5625 2050);
PAINT GREEN (5625 2050);
DISPLAY INVISIBLE (5625 2050);
FORCEADD Q_CAP..1
(5600 2500);
FORCEPROP 1 LAST LOCATION PC415_4
J 0
(5650 2650);
DISPLAY 0.489362 (5650 2650);
PAINT SKYBLUE (5650 2650);
FORCEPROP 0 LAST $SEC 1
J 0
(5650 2700);
DISPLAY 0.680851 (5650 2700);
PAINT MONO (5650 2700);
DISPLAY INVISIBLE (5650 2700);
FORCEPROP 0 LAST CDS_SEC 1
J 0
(5650 2700);
DISPLAY 1.021277 (5650 2700);
DISPLAY INVISIBLE (5650 2700);
FORCEPROP 1 LASTPIN (5600 2600) $PN 1
J 0
(5610 2580);
DISPLAY 0.489362 (5610 2580);
PAINT MONO (5610 2580);
FORCEPROP 1 LASTPIN (5600 2400) $PN 2
J 0
(5610 2380);
DISPLAY 0.489362 (5610 2380);
PAINT MONO (5610 2380);
FORCEPROP 1 LAST MATERIAL X6S
J 0
(5650 2450);
DISPLAY 0.489362 (5650 2450);
PAINT SKYBLUE (5650 2450);
FORCEPROP 1 LAST TOLERANCE 10%
J 0
(5650 2500);
DISPLAY 0.489362 (5650 2500);
PAINT SKYBLUE (5650 2500);
FORCEPROP 1 LAST VALUE 10UF
J 0
(5650 2600);
DISPLAY 0.489362 (5650 2600);
PAINT SKYBLUE (5650 2600);
FORCEPROP 1 LAST PART_NUMBER CH6104KEA00
J 0
(5650 2350);
DISPLAY 0.489362 (5650 2350);
PAINT SKYBLUE (5650 2350);
FORCEPROP 1 LAST VOLTAGE 25V
J 0
(5650 2550);
DISPLAY 0.489362 (5650 2550);
PAINT SKYBLUE (5650 2550);
FORCEPROP 1 LAST PACK_TYPE C0805
J 0
(5650 2400);
DISPLAY 0.489362 (5650 2400);
PAINT SKYBLUE (5650 2400);
FORCEPROP 2 LAST CDS_LIB pure_quanta
J 0
(5600 2500);
DISPLAY INVISIBLE (5600 2500);
FORCEPROP 1 LAST PATH I42
J 0
(5650 2650);
DISPLAY 0.978723 (5650 2650);
PAINT WHITE (5650 2650);
DISPLAY INVISIBLE (5650 2650);
FORCEADD VCC_CORE..1
(5600 2850);
FORCEPROP 3 LASTPIN (5600 2800) SIG_NAME SW_P12V_STBY_PVDDCR_CPU1_P1_FLT\g
J 0
(5610 2810);
DISPLAY 0.659574 (5610 2810);
PAINT MONO (5610 2810);
DISPLAY INVISIBLE (5610 2810);
FORCEPROP 1 LAST HDL_POWER SW_P12V_STBY_PVDDCR_CPU1_P1_FLT
J 1
(5600 2900);
DISPLAY 0.489362 (5600 2900);
PAINT GREEN (5600 2900);
FORCEPROP 2 LAST CDS_LIB pure_quanta_power
J 0
(5600 2850);
DISPLAY INVISIBLE (5600 2850);
FORCEPROP 1 LAST PATH I43
J 0
(5650 2875);
DISPLAY 0.872340 (5650 2875);
PAINT AQUA (5650 2875);
DISPLAY INVISIBLE (5650 2875);
FORCEADD OFFPAGE..1
(1775 1000);
FORCEPROP 2 LAST $XR0 193 
J 0
(1493 1000);
DISPLAY 0.638298 (1493 1000);
PAINT MONO (1493 1000);
FORCEPROP 2 LAST PATH I5
J 0
(1350 1050);
DISPLAY 1.021277 (1350 1050);
DISPLAY INVISIBLE (1350 1050);
FORCEPROP 1 LAST COMMENT_BODY TRUE
J 0
(1900 900);
DISPLAY 0.872340 (1900 900);
PAINT GREEN (1900 900);
DISPLAY INVISIBLE (1900 900);
FORCEPROP 1 LAST OFFPAGE TRUE
J 0
(2100 875);
DISPLAY 0.872340 (2100 875);
PAINT GREEN (2100 875);
DISPLAY INVISIBLE (2100 875);
FORCEPROP 2 LAST CDS_LIB standard
J 0
(1775 1000);
DISPLAY INVISIBLE (1775 1000);
FORCEADD Q_CAP..1
(4475 5350);
FORCEPROP 1 LAST LOCATION PC408_3
J 0
(4525 5500);
DISPLAY 0.489362 (4525 5500);
PAINT SKYBLUE (4525 5500);
FORCEPROP 0 LAST $SEC 1
J 0
(4525 5550);
DISPLAY 0.680851 (4525 5550);
PAINT MONO (4525 5550);
DISPLAY INVISIBLE (4525 5550);
FORCEPROP 0 LAST CDS_SEC 1
J 0
(4525 5550);
DISPLAY 1.021277 (4525 5550);
DISPLAY INVISIBLE (4525 5550);
FORCEPROP 1 LASTPIN (4475 5450) $PN 1
J 0
(4485 5430);
DISPLAY 0.489362 (4485 5430);
PAINT MONO (4485 5430);
FORCEPROP 1 LASTPIN (4475 5250) $PN 2
J 0
(4485 5230);
DISPLAY 0.489362 (4485 5230);
PAINT MONO (4485 5230);
FORCEPROP 1 LAST MATERIAL X6S
J 0
(4525 5300);
DISPLAY 0.489362 (4525 5300);
PAINT SKYBLUE (4525 5300);
FORCEPROP 1 LAST TOLERANCE 10%
J 0
(4525 5350);
DISPLAY 0.489362 (4525 5350);
PAINT SKYBLUE (4525 5350);
FORCEPROP 1 LAST VALUE 1UF
J 0
(4525 5450);
DISPLAY 0.489362 (4525 5450);
PAINT SKYBLUE (4525 5450);
FORCEPROP 1 LAST PART_NUMBER CH5104KEB02
J 0
(4525 5200);
DISPLAY 0.489362 (4525 5200);
PAINT SKYBLUE (4525 5200);
FORCEPROP 1 LAST VOLTAGE 25V
J 0
(4525 5400);
DISPLAY 0.489362 (4525 5400);
PAINT SKYBLUE (4525 5400);
FORCEPROP 1 LAST PACK_TYPE C0402
J 0
(4525 5250);
DISPLAY 0.489362 (4525 5250);
PAINT SKYBLUE (4525 5250);
FORCEPROP 2 LAST CDS_LIB pure_quanta
J 0
(4475 5350);
DISPLAY INVISIBLE (4475 5350);
FORCEPROP 1 LAST PATH I50
J 0
(4525 5500);
DISPLAY 0.978723 (4525 5500);
PAINT WHITE (4525 5500);
DISPLAY INVISIBLE (4525 5500);
FORCEADD Q_CAP..1
(4875 5350);
FORCEPROP 1 LAST LOCATION PC410_3
J 0
(4925 5500);
DISPLAY 0.489362 (4925 5500);
PAINT SKYBLUE (4925 5500);
FORCEPROP 0 LAST $SEC 1
J 0
(4925 5550);
DISPLAY 0.680851 (4925 5550);
PAINT MONO (4925 5550);
DISPLAY INVISIBLE (4925 5550);
FORCEPROP 0 LAST CDS_SEC 1
J 0
(4925 5550);
DISPLAY 1.021277 (4925 5550);
DISPLAY INVISIBLE (4925 5550);
FORCEPROP 1 LASTPIN (4875 5450) $PN 1
J 0
(4885 5430);
DISPLAY 0.489362 (4885 5430);
PAINT MONO (4885 5430);
FORCEPROP 1 LASTPIN (4875 5250) $PN 2
J 0
(4885 5230);
DISPLAY 0.489362 (4885 5230);
PAINT MONO (4885 5230);
FORCEPROP 1 LAST MATERIAL X6S
J 0
(4925 5300);
DISPLAY 0.489362 (4925 5300);
PAINT SKYBLUE (4925 5300);
FORCEPROP 1 LAST TOLERANCE 10%
J 0
(4925 5350);
DISPLAY 0.489362 (4925 5350);
PAINT SKYBLUE (4925 5350);
FORCEPROP 1 LAST VALUE 10UF
J 0
(4925 5450);
DISPLAY 0.489362 (4925 5450);
PAINT SKYBLUE (4925 5450);
FORCEPROP 1 LAST PART_NUMBER CH6104KEA00
J 0
(4925 5200);
DISPLAY 0.489362 (4925 5200);
PAINT SKYBLUE (4925 5200);
FORCEPROP 1 LAST VOLTAGE 25V
J 0
(4925 5400);
DISPLAY 0.489362 (4925 5400);
PAINT SKYBLUE (4925 5400);
FORCEPROP 1 LAST PACK_TYPE C0805
J 0
(4925 5250);
DISPLAY 0.489362 (4925 5250);
PAINT SKYBLUE (4925 5250);
FORCEPROP 2 LAST CDS_LIB pure_quanta
J 0
(4875 5350);
DISPLAY INVISIBLE (4875 5350);
FORCEPROP 1 LAST PATH I51
J 0
(4925 5500);
DISPLAY 0.978723 (4925 5500);
PAINT WHITE (4925 5500);
DISPLAY INVISIBLE (4925 5500);
FORCEADD Q_CAP..1
(5275 5350);
FORCEPROP 1 LAST LOCATION PC412_3
J 0
(5325 5500);
DISPLAY 0.489362 (5325 5500);
PAINT SKYBLUE (5325 5500);
FORCEPROP 0 LAST $SEC 1
J 0
(5325 5550);
DISPLAY 0.680851 (5325 5550);
PAINT MONO (5325 5550);
DISPLAY INVISIBLE (5325 5550);
FORCEPROP 0 LAST CDS_SEC 1
J 0
(5325 5550);
DISPLAY 1.021277 (5325 5550);
DISPLAY INVISIBLE (5325 5550);
FORCEPROP 1 LASTPIN (5275 5450) $PN 1
J 0
(5285 5430);
DISPLAY 0.489362 (5285 5430);
PAINT MONO (5285 5430);
FORCEPROP 1 LASTPIN (5275 5250) $PN 2
J 0
(5285 5230);
DISPLAY 0.489362 (5285 5230);
PAINT MONO (5285 5230);
FORCEPROP 1 LAST MATERIAL X6S
J 0
(5325 5300);
DISPLAY 0.489362 (5325 5300);
PAINT SKYBLUE (5325 5300);
FORCEPROP 1 LAST TOLERANCE 10%
J 0
(5325 5350);
DISPLAY 0.489362 (5325 5350);
PAINT SKYBLUE (5325 5350);
FORCEPROP 1 LAST VALUE 10UF
J 0
(5325 5450);
DISPLAY 0.489362 (5325 5450);
PAINT SKYBLUE (5325 5450);
FORCEPROP 1 LAST VOLTAGE 25V
J 0
(5325 5400);
DISPLAY 0.489362 (5325 5400);
PAINT SKYBLUE (5325 5400);
FORCEPROP 1 LAST PACK_TYPE C0805
J 0
(5325 5250);
DISPLAY 0.489362 (5325 5250);
PAINT SKYBLUE (5325 5250);
FORCEPROP 1 LAST PART_NUMBER CH6104KEA00
J 0
(5325 5200);
DISPLAY 0.489362 (5325 5200);
PAINT SKYBLUE (5325 5200);
FORCEPROP 2 LAST CDS_LIB pure_quanta
J 0
(5275 5350);
DISPLAY INVISIBLE (5275 5350);
FORCEPROP 1 LAST PATH I55
J 0
(5325 5500);
DISPLAY 0.978723 (5325 5500);
PAINT WHITE (5325 5500);
DISPLAY INVISIBLE (5325 5500);
FORCEADD Q_CAP..1
(5650 5350);
FORCEPROP 1 LAST LOCATION PC416_3
J 0
(5700 5500);
DISPLAY 0.489362 (5700 5500);
PAINT SKYBLUE (5700 5500);
FORCEPROP 0 LAST $SEC 1
J 0
(5700 5550);
DISPLAY 0.680851 (5700 5550);
PAINT MONO (5700 5550);
DISPLAY INVISIBLE (5700 5550);
FORCEPROP 0 LAST CDS_SEC 1
J 0
(5700 5550);
DISPLAY 1.021277 (5700 5550);
DISPLAY INVISIBLE (5700 5550);
FORCEPROP 1 LASTPIN (5650 5450) $PN 1
J 0
(5660 5430);
DISPLAY 0.489362 (5660 5430);
PAINT MONO (5660 5430);
FORCEPROP 1 LASTPIN (5650 5250) $PN 2
J 0
(5660 5230);
DISPLAY 0.489362 (5660 5230);
PAINT MONO (5660 5230);
FORCEPROP 1 LAST MATERIAL X6S
J 0
(5700 5300);
DISPLAY 0.489362 (5700 5300);
PAINT SKYBLUE (5700 5300);
FORCEPROP 1 LAST TOLERANCE 10%
J 0
(5700 5350);
DISPLAY 0.489362 (5700 5350);
PAINT SKYBLUE (5700 5350);
FORCEPROP 1 LAST VALUE 10UF
J 0
(5700 5450);
DISPLAY 0.489362 (5700 5450);
PAINT SKYBLUE (5700 5450);
FORCEPROP 1 LAST PART_NUMBER CH6104KEA00
J 0
(5700 5200);
DISPLAY 0.489362 (5700 5200);
PAINT SKYBLUE (5700 5200);
FORCEPROP 1 LAST VOLTAGE 25V
J 0
(5700 5400);
DISPLAY 0.489362 (5700 5400);
PAINT SKYBLUE (5700 5400);
FORCEPROP 1 LAST PACK_TYPE C0805
J 0
(5700 5250);
DISPLAY 0.489362 (5700 5250);
PAINT SKYBLUE (5700 5250);
FORCEPROP 2 LAST CDS_LIB pure_quanta
J 0
(5650 5350);
DISPLAY INVISIBLE (5650 5350);
FORCEPROP 1 LAST PATH I56
J 0
(5700 5500);
DISPLAY 0.978723 (5700 5500);
PAINT WHITE (5700 5500);
DISPLAY INVISIBLE (5700 5500);
FORCEADD UNIVERSAL_GND..1
(5650 5000);
FORCEPROP 3 LASTPIN (5650 5050) SIG_NAME GND\g
J 0
(5660 5060);
DISPLAY 0.659574 (5660 5060);
PAINT MONO (5660 5060);
DISPLAY INVISIBLE (5660 5060);
FORCEPROP 2 LAST CDS_LIB pure_quanta_power
J 0
(5650 5000);
PAINT MONO (5650 5000);
DISPLAY INVISIBLE (5650 5000);
FORCEPROP 1 LAST PATH I57
J 0
(5725 5000);
DISPLAY 0.872340 (5725 5000);
PAINT AQUA (5725 5000);
DISPLAY INVISIBLE (5725 5000);
FORCEPROP 1 LAST HDL_POWER GND
J 1
(5675 4925);
DISPLAY 0.872340 (5675 4925);
PAINT GREEN (5675 4925);
DISPLAY INVISIBLE (5675 4925);
FORCEADD VCC_CORE..1
(5650 5700);
FORCEPROP 3 LASTPIN (5650 5650) SIG_NAME SW_P12V_STBY_PVDDCR_CPU1_P1_FLT\g
J 0
(5660 5660);
DISPLAY 0.659574 (5660 5660);
PAINT MONO (5660 5660);
DISPLAY INVISIBLE (5660 5660);
FORCEPROP 1 LAST HDL_POWER SW_P12V_STBY_PVDDCR_CPU1_P1_FLT
J 1
(5650 5750);
DISPLAY 0.489362 (5650 5750);
PAINT GREEN (5650 5750);
FORCEPROP 2 LAST CDS_LIB pure_quanta_power
J 0
(5650 5700);
DISPLAY INVISIBLE (5650 5700);
FORCEPROP 1 LAST PATH I58
J 0
(5700 5725);
DISPLAY 0.872340 (5700 5725);
PAINT AQUA (5700 5725);
DISPLAY INVISIBLE (5700 5725);
FORCEADD OFFPAGE..1
(1775 1500);
FORCEPROP 2 LAST $XR5 199 
J 0
(893 1500);
DISPLAY 0.638298 (893 1500);
PAINT MONO (893 1500);
FORCEPROP 2 LAST $XR4 198 
J 0
(1013 1500);
DISPLAY 0.638298 (1013 1500);
PAINT MONO (1013 1500);
FORCEPROP 2 LAST $XR3 196 
J 0
(1133 1500);
DISPLAY 0.638298 (1133 1500);
PAINT MONO (1133 1500);
FORCEPROP 2 LAST $XR2 195 
J 0
(1253 1500);
DISPLAY 0.638298 (1253 1500);
PAINT MONO (1253 1500);
FORCEPROP 2 LAST $XR1 194 
J 0
(1373 1500);
DISPLAY 0.638298 (1373 1500);
PAINT MONO (1373 1500);
FORCEPROP 2 LAST $XR0 193 
J 0
(1493 1500);
DISPLAY 0.638298 (1493 1500);
PAINT MONO (1493 1500);
FORCEPROP 2 LAST PATH I6
J 0
(1525 1550);
DISPLAY 1.021277 (1525 1550);
DISPLAY INVISIBLE (1525 1550);
FORCEPROP 1 LAST COMMENT_BODY TRUE
J 0
(1900 1400);
DISPLAY 0.872340 (1900 1400);
PAINT GREEN (1900 1400);
DISPLAY INVISIBLE (1900 1400);
FORCEPROP 1 LAST OFFPAGE TRUE
J 0
(2100 1375);
DISPLAY 0.872340 (2100 1375);
PAINT GREEN (2100 1375);
DISPLAY INVISIBLE (2100 1375);
FORCEPROP 2 LAST CDS_LIB standard
J 0
(1775 1500);
DISPLAY INVISIBLE (1775 1500);
FORCEADD OFFPAGE..5
(1775 1600);
FORCEPROP 2 LAST $XR0 193 
J 0
(1520 1600);
DISPLAY 0.638298 (1520 1600);
PAINT MONO (1520 1600);
FORCEPROP 2 LAST PATH I7
J 0
(1500 1650);
DISPLAY 1.021277 (1500 1650);
DISPLAY INVISIBLE (1500 1650);
FORCEPROP 1 LAST COMMENT_BODY TRUE
J 0
(1875 1525);
DISPLAY 0.872340 (1875 1525);
PAINT GREEN (1875 1525);
DISPLAY INVISIBLE (1875 1525);
FORCEPROP 1 LAST OFFPAGE TRUE
J 0
(2100 1475);
DISPLAY 0.872340 (2100 1475);
PAINT GREEN (2100 1475);
DISPLAY INVISIBLE (2100 1475);
FORCEPROP 2 LAST CDS_LIB standard
J 0
(1775 1600);
DISPLAY INVISIBLE (1775 1600);
FORCEADD OFFPAGE..3
(7625 4175);
FORCEPROP 2 LAST $XR0 195 
J 0
(7839 4175);
DISPLAY 0.638298 (7839 4175);
PAINT MONO (7839 4175);
FORCEPROP 2 LAST PATH I73
J 0
(7825 4250);
DISPLAY 1.021277 (7825 4250);
DISPLAY INVISIBLE (7825 4250);
FORCEPROP 1 LAST COMMENT_BODY TRUE
J 0
(7575 4075);
DISPLAY 0.872340 (7575 4075);
PAINT GREEN (7575 4075);
DISPLAY INVISIBLE (7575 4075);
FORCEPROP 1 LAST OFFPAGE TRUE
J 0
(7950 4050);
DISPLAY 0.872340 (7950 4050);
PAINT GREEN (7950 4050);
DISPLAY INVISIBLE (7950 4050);
FORCEPROP 2 LAST CDS_LIB standard
J 0
(7625 4175);
DISPLAY INVISIBLE (7625 4175);
FORCEADD OFFPAGE..6
(5550 4175);
FORCEPROP 2 LAST $XR0 194 
J 0
(5270 4175);
DISPLAY 0.638298 (5270 4175);
PAINT MONO (5270 4175);
FORCEPROP 2 LAST PATH I75
J 0
(5600 4250);
DISPLAY 1.021277 (5600 4250);
DISPLAY INVISIBLE (5600 4250);
FORCEPROP 1 LAST COMMENT_BODY TRUE
J 0
(5650 4100);
DISPLAY 0.872340 (5650 4100);
PAINT GREEN (5650 4100);
DISPLAY INVISIBLE (5650 4100);
FORCEPROP 1 LAST OFFPAGE TRUE
J 0
(5875 4050);
DISPLAY 0.872340 (5875 4050);
PAINT GREEN (5875 4050);
DISPLAY INVISIBLE (5875 4050);
FORCEPROP 2 LAST CDS_LIB standard
J 0
(5550 4175);
DISPLAY INVISIBLE (5550 4175);
FORCEADD Q_RES..1
(5850 3250);
FORCEPROP 1 LAST LOCATION PR269
J 0
(5800 3275);
DISPLAY 0.489362 (5800 3275);
PAINT SKYBLUE (5800 3275);
FORCEPROP 0 LAST $SEC 1
J 0
(6100 3400);
DISPLAY 0.680851 (6100 3400);
PAINT MONO (6100 3400);
DISPLAY INVISIBLE (6100 3400);
FORCEPROP 0 LAST CDS_SEC 1
J 0
(6100 3400);
DISPLAY 1.021277 (6100 3400);
DISPLAY INVISIBLE (6100 3400);
FORCEPROP 1 LASTPIN (5750 3250) $PN 1
J 0
(5762 3262);
DISPLAY 0.489362 (5762 3262);
PAINT MONO (5762 3262);
FORCEPROP 1 LASTPIN (5950 3250) $PN 2
J 0
(5912 3262);
DISPLAY 0.489362 (5912 3262);
PAINT MONO (5912 3262);
FORCEPROP 1 LAST WATTAGE 1/16W
J 2
(6075 3325);
DISPLAY 0.489362 (6075 3325);
PAINT SKYBLUE (6075 3325);
FORCEPROP 1 LAST MATERIAL CHIP
J 0
(5975 3275);
DISPLAY 0.489362 (5975 3275);
PAINT SKYBLUE (5975 3275);
FORCEPROP 1 LAST TOLERANCE 5%
J 0
(5675 3275);
DISPLAY 0.489362 (5675 3275);
PAINT SKYBLUE (5675 3275);
FORCEPROP 1 LAST VALUE 0
J 2
(5650 3275);
DISPLAY 0.489362 (5650 3275);
PAINT SKYBLUE (5650 3275);
FORCEPROP 1 LAST PART_NUMBER CS00002JB38
J 0
(5550 3200);
DISPLAY 0.489362 (5550 3200);
PAINT SKYBLUE (5550 3200);
FORCEPROP 1 LAST PACK_TYPE 0402LF
J 0
(5950 3200);
DISPLAY 0.489362 (5950 3200);
PAINT SKYBLUE (5950 3200);
FORCEPROP 2 LAST CDS_LIB pure_quanta
J 0
(5850 3250);
DISPLAY INVISIBLE (5850 3250);
FORCEPROP 1 LAST PATH I76
J 0
(5800 3400);
DISPLAY 0.978723 (5800 3400);
PAINT WHITE (5800 3400);
DISPLAY INVISIBLE (5800 3400);
FORCEADD VCC_CORE..1
(8550 4525);
FORCEPROP 3 LASTPIN (8550 4475) SIG_NAME PVDDCR_CPU1_P1\g
J 0
(8560 4485);
DISPLAY 0.659574 (8560 4485);
PAINT MONO (8560 4485);
DISPLAY INVISIBLE (8560 4485);
FORCEPROP 1 LAST HDL_POWER PVDDCR_CPU1_P1
J 1
(8550 4575);
DISPLAY 0.489362 (8550 4575);
PAINT GREEN (8550 4575);
FORCEPROP 2 LAST CDS_LIB pure_quanta_power
J 0
(8550 4525);
DISPLAY INVISIBLE (8550 4525);
FORCEPROP 1 LAST PATH I77
J 0
(8600 4550);
DISPLAY 0.872340 (8600 4550);
PAINT AQUA (8600 4550);
DISPLAY INVISIBLE (8600 4550);
FORCEADD Q_CAP..1
(8550 4225);
FORCEPROP 1 LAST LOCATION PC419_3
J 0
(8600 4350);
DISPLAY 0.489362 (8600 4350);
PAINT SKYBLUE (8600 4350);
FORCEPROP 0 LAST $SEC 1
J 0
(8600 4400);
DISPLAY 0.680851 (8600 4400);
PAINT MONO (8600 4400);
DISPLAY INVISIBLE (8600 4400);
FORCEPROP 0 LAST CDS_SEC 1
J 0
(8600 4400);
DISPLAY 1.021277 (8600 4400);
DISPLAY INVISIBLE (8600 4400);
FORCEPROP 1 LASTPIN (8550 4325) $PN 1
J 0
(8560 4305);
DISPLAY 0.489362 (8560 4305);
PAINT MONO (8560 4305);
FORCEPROP 1 LASTPIN (8550 4125) $PN 2
J 0
(8560 4105);
DISPLAY 0.489362 (8560 4105);
PAINT MONO (8560 4105);
FORCEPROP 1 LAST MATERIAL X6S
J 0
(8600 4150);
DISPLAY 0.489362 (8600 4150);
PAINT SKYBLUE (8600 4150);
FORCEPROP 1 LAST TOLERANCE 20%
J 0
(8600 4200);
DISPLAY 0.489362 (8600 4200);
PAINT SKYBLUE (8600 4200);
FORCEPROP 1 LAST VALUE 22UF
J 0
(8600 4300);
DISPLAY 0.489362 (8600 4300);
PAINT SKYBLUE (8600 4300);
FORCEPROP 1 LAST PART_NUMBER TMP_QCH622KMEA01
J 0
(8600 4050);
DISPLAY 0.489362 (8600 4050);
PAINT SKYBLUE (8600 4050);
FORCEPROP 1 LAST VOLTAGE 4V
J 0
(8600 4250);
DISPLAY 0.489362 (8600 4250);
PAINT SKYBLUE (8600 4250);
FORCEPROP 1 LAST PACK_TYPE 0805
J 0
(8600 4100);
DISPLAY 0.489362 (8600 4100);
PAINT SKYBLUE (8600 4100);
FORCEPROP 2 LAST CDS_LIB pure_quanta
J 0
(8550 4225);
DISPLAY INVISIBLE (8550 4225);
FORCEPROP 1 LAST PATH I78
J 0
(8600 4375);
DISPLAY 0.978723 (8600 4375);
PAINT WHITE (8600 4375);
DISPLAY INVISIBLE (8600 4375);
FORCEADD Q_CAP..1
(8125 4225);
FORCEPROP 1 LAST LOCATION PC417_3
J 0
(8175 4350);
DISPLAY 0.489362 (8175 4350);
PAINT SKYBLUE (8175 4350);
FORCEPROP 0 LAST $SEC 1
J 0
(8175 4400);
DISPLAY 0.680851 (8175 4400);
PAINT MONO (8175 4400);
DISPLAY INVISIBLE (8175 4400);
FORCEPROP 0 LAST CDS_SEC 1
J 0
(8175 4400);
DISPLAY 1.021277 (8175 4400);
DISPLAY INVISIBLE (8175 4400);
FORCEPROP 1 LASTPIN (8125 4325) $PN 1
J 0
(8135 4305);
DISPLAY 0.489362 (8135 4305);
PAINT MONO (8135 4305);
FORCEPROP 1 LASTPIN (8125 4125) $PN 2
J 0
(8135 4105);
DISPLAY 0.489362 (8135 4105);
PAINT MONO (8135 4105);
FORCEPROP 1 LAST MATERIAL X6S
J 0
(8175 4150);
DISPLAY 0.489362 (8175 4150);
PAINT SKYBLUE (8175 4150);
FORCEPROP 1 LAST TOLERANCE 20%
J 0
(8175 4200);
DISPLAY 0.489362 (8175 4200);
PAINT SKYBLUE (8175 4200);
FORCEPROP 1 LAST VALUE 22UF
J 0
(8175 4300);
DISPLAY 0.489362 (8175 4300);
PAINT SKYBLUE (8175 4300);
FORCEPROP 1 LAST PART_NUMBER TMP_QCH622KMEA01
J 0
(8175 4050);
DISPLAY 0.489362 (8175 4050);
PAINT SKYBLUE (8175 4050);
FORCEPROP 1 LAST VOLTAGE 4V
J 0
(8175 4250);
DISPLAY 0.489362 (8175 4250);
PAINT SKYBLUE (8175 4250);
FORCEPROP 1 LAST PACK_TYPE 0805
J 0
(8175 4100);
DISPLAY 0.489362 (8175 4100);
PAINT SKYBLUE (8175 4100);
FORCEPROP 2 LAST CDS_LIB pure_quanta
J 0
(8125 4225);
DISPLAY INVISIBLE (8125 4225);
FORCEPROP 1 LAST PATH I79
J 0
(8175 4375);
DISPLAY 0.978723 (8175 4375);
PAINT WHITE (8175 4375);
DISPLAY INVISIBLE (8175 4375);
FORCEADD UNIVERSAL_GND..1
(8550 3900);
FORCEPROP 3 LASTPIN (8550 3950) SIG_NAME GND\g
J 0
(8560 3960);
DISPLAY 0.659574 (8560 3960);
PAINT MONO (8560 3960);
DISPLAY INVISIBLE (8560 3960);
FORCEPROP 2 LAST CDS_LIB pure_quanta_power
J 0
(8550 3900);
PAINT MONO (8550 3900);
DISPLAY INVISIBLE (8550 3900);
FORCEPROP 1 LAST PATH I80
J 0
(8625 3900);
DISPLAY 0.872340 (8625 3900);
PAINT AQUA (8625 3900);
DISPLAY INVISIBLE (8625 3900);
FORCEPROP 1 LAST HDL_POWER GND
J 1
(8575 3825);
DISPLAY 0.872340 (8575 3825);
PAINT GREEN (8575 3825);
DISPLAY INVISIBLE (8575 3825);
FORCEADD OFFPAGE..6
(5625 1350);
FORCEPROP 2 LAST $XR0 195 
J 0
(5345 1350);
DISPLAY 0.638298 (5345 1350);
PAINT MONO (5345 1350);
FORCEPROP 2 LAST PATH I91
J 0
(5675 1425);
DISPLAY 1.021277 (5675 1425);
DISPLAY INVISIBLE (5675 1425);
FORCEPROP 1 LAST COMMENT_BODY TRUE
J 0
(5725 1275);
DISPLAY 0.872340 (5725 1275);
PAINT GREEN (5725 1275);
DISPLAY INVISIBLE (5725 1275);
FORCEPROP 1 LAST OFFPAGE TRUE
J 0
(5950 1225);
DISPLAY 0.872340 (5950 1225);
PAINT GREEN (5950 1225);
DISPLAY INVISIBLE (5950 1225);
FORCEPROP 2 LAST CDS_LIB standard
J 0
(5625 1350);
DISPLAY INVISIBLE (5625 1350);
FORCEADD Q_RES..1
(5925 600);
FORCEPROP 1 LAST LOCATION PR268
J 0
(5875 625);
DISPLAY 0.489362 (5875 625);
PAINT SKYBLUE (5875 625);
FORCEPROP 0 LAST $SEC 1
J 0
(6175 750);
DISPLAY 0.680851 (6175 750);
PAINT MONO (6175 750);
DISPLAY INVISIBLE (6175 750);
FORCEPROP 0 LAST CDS_SEC 1
J 0
(6175 750);
DISPLAY 1.021277 (6175 750);
DISPLAY INVISIBLE (6175 750);
FORCEPROP 1 LASTPIN (5825 600) $PN 1
J 0
(5837 612);
DISPLAY 0.489362 (5837 612);
PAINT MONO (5837 612);
FORCEPROP 1 LASTPIN (6025 600) $PN 2
J 0
(5987 612);
DISPLAY 0.489362 (5987 612);
PAINT MONO (5987 612);
FORCEPROP 1 LAST WATTAGE 1/16W
J 2
(6150 675);
DISPLAY 0.489362 (6150 675);
PAINT SKYBLUE (6150 675);
FORCEPROP 1 LAST MATERIAL CHIP
J 0
(6050 625);
DISPLAY 0.489362 (6050 625);
PAINT SKYBLUE (6050 625);
FORCEPROP 1 LAST TOLERANCE 5%
J 0
(5750 625);
DISPLAY 0.489362 (5750 625);
PAINT SKYBLUE (5750 625);
FORCEPROP 1 LAST VALUE 0
J 2
(5725 625);
DISPLAY 0.489362 (5725 625);
PAINT SKYBLUE (5725 625);
FORCEPROP 1 LAST PART_NUMBER CS00002JB38
J 0
(5625 550);
DISPLAY 0.489362 (5625 550);
PAINT SKYBLUE (5625 550);
FORCEPROP 1 LAST PACK_TYPE 0402LF
J 0
(6025 550);
DISPLAY 0.489362 (6025 550);
PAINT SKYBLUE (6025 550);
FORCEPROP 2 LAST CDS_LIB pure_quanta
J 0
(5925 600);
DISPLAY INVISIBLE (5925 600);
FORCEPROP 1 LAST PATH I92
J 0
(5875 750);
DISPLAY 0.978723 (5875 750);
PAINT WHITE (5875 750);
DISPLAY INVISIBLE (5875 750);
FORCEADD VCC_CORE..1
(8700 1700);
FORCEPROP 3 LASTPIN (8700 1650) SIG_NAME PVDDCR_CPU1_P1\g
J 0
(8710 1660);
DISPLAY 0.659574 (8710 1660);
PAINT MONO (8710 1660);
DISPLAY INVISIBLE (8710 1660);
FORCEPROP 1 LAST HDL_POWER PVDDCR_CPU1_P1
J 1
(8700 1750);
DISPLAY 0.489362 (8700 1750);
PAINT GREEN (8700 1750);
FORCEPROP 2 LAST CDS_LIB pure_quanta_power
J 0
(8700 1700);
DISPLAY INVISIBLE (8700 1700);
FORCEPROP 1 LAST PATH I93
J 0
(8750 1725);
DISPLAY 0.872340 (8750 1725);
PAINT AQUA (8750 1725);
DISPLAY INVISIBLE (8750 1725);
FORCEADD UNIVERSAL_GND..1
(8700 1075);
FORCEPROP 3 LASTPIN (8700 1125) SIG_NAME GND\g
J 0
(8710 1135);
DISPLAY 0.659574 (8710 1135);
PAINT MONO (8710 1135);
DISPLAY INVISIBLE (8710 1135);
FORCEPROP 2 LAST CDS_LIB pure_quanta_power
J 0
(8700 1075);
PAINT MONO (8700 1075);
DISPLAY INVISIBLE (8700 1075);
FORCEPROP 1 LAST PATH I94
J 0
(8775 1075);
DISPLAY 0.872340 (8775 1075);
PAINT AQUA (8775 1075);
DISPLAY INVISIBLE (8775 1075);
FORCEPROP 1 LAST HDL_POWER GND
J 1
(8725 1000);
DISPLAY 0.872340 (8725 1000);
PAINT GREEN (8725 1000);
DISPLAY INVISIBLE (8725 1000);
FORCEADD Q_CAP..1
(8700 1400);
FORCEPROP 1 LAST LOCATION PC420_4
J 0
(8750 1525);
DISPLAY 0.489362 (8750 1525);
PAINT SKYBLUE (8750 1525);
FORCEPROP 0 LAST $SEC 1
J 0
(8750 1575);
DISPLAY 0.680851 (8750 1575);
PAINT MONO (8750 1575);
DISPLAY INVISIBLE (8750 1575);
FORCEPROP 0 LAST CDS_SEC 1
J 0
(8750 1575);
DISPLAY 1.021277 (8750 1575);
DISPLAY INVISIBLE (8750 1575);
FORCEPROP 1 LASTPIN (8700 1500) $PN 1
J 0
(8710 1480);
DISPLAY 0.489362 (8710 1480);
PAINT MONO (8710 1480);
FORCEPROP 1 LASTPIN (8700 1300) $PN 2
J 0
(8710 1280);
DISPLAY 0.489362 (8710 1280);
PAINT MONO (8710 1280);
FORCEPROP 1 LAST MATERIAL X6S
J 0
(8750 1325);
DISPLAY 0.489362 (8750 1325);
PAINT SKYBLUE (8750 1325);
FORCEPROP 1 LAST TOLERANCE 20%
J 0
(8750 1375);
DISPLAY 0.489362 (8750 1375);
PAINT SKYBLUE (8750 1375);
FORCEPROP 1 LAST VALUE 22UF
J 0
(8750 1475);
DISPLAY 0.489362 (8750 1475);
PAINT SKYBLUE (8750 1475);
FORCEPROP 1 LAST PART_NUMBER TMP_QCH622KMEA01
J 0
(8750 1225);
DISPLAY 0.489362 (8750 1225);
PAINT SKYBLUE (8750 1225);
FORCEPROP 1 LAST VOLTAGE 4V
J 0
(8750 1425);
DISPLAY 0.489362 (8750 1425);
PAINT SKYBLUE (8750 1425);
FORCEPROP 1 LAST PACK_TYPE 0805
J 0
(8750 1275);
DISPLAY 0.489362 (8750 1275);
PAINT SKYBLUE (8750 1275);
FORCEPROP 2 LAST CDS_LIB pure_quanta
J 0
(8700 1400);
DISPLAY INVISIBLE (8700 1400);
FORCEPROP 1 LAST PATH I95
J 0
(8750 1550);
DISPLAY 0.978723 (8750 1550);
PAINT WHITE (8750 1550);
DISPLAY INVISIBLE (8750 1550);
FORCEADD Q_CAP..1
(8275 1400);
FORCEPROP 1 LAST LOCATION PC418_4
J 0
(8325 1525);
DISPLAY 0.489362 (8325 1525);
PAINT SKYBLUE (8325 1525);
FORCEPROP 0 LAST $SEC 1
J 0
(8325 1575);
DISPLAY 0.680851 (8325 1575);
PAINT MONO (8325 1575);
DISPLAY INVISIBLE (8325 1575);
FORCEPROP 0 LAST CDS_SEC 1
J 0
(8325 1575);
DISPLAY 1.021277 (8325 1575);
DISPLAY INVISIBLE (8325 1575);
FORCEPROP 1 LASTPIN (8275 1500) $PN 1
J 0
(8285 1480);
DISPLAY 0.489362 (8285 1480);
PAINT MONO (8285 1480);
FORCEPROP 1 LASTPIN (8275 1300) $PN 2
J 0
(8285 1280);
DISPLAY 0.489362 (8285 1280);
PAINT MONO (8285 1280);
FORCEPROP 1 LAST MATERIAL X6S
J 0
(8325 1325);
DISPLAY 0.489362 (8325 1325);
PAINT SKYBLUE (8325 1325);
FORCEPROP 1 LAST TOLERANCE 20%
J 0
(8325 1375);
DISPLAY 0.489362 (8325 1375);
PAINT SKYBLUE (8325 1375);
FORCEPROP 1 LAST VALUE 22UF
J 0
(8325 1475);
DISPLAY 0.489362 (8325 1475);
PAINT SKYBLUE (8325 1475);
FORCEPROP 1 LAST PART_NUMBER TMP_QCH622KMEA01
J 0
(8325 1225);
DISPLAY 0.489362 (8325 1225);
PAINT SKYBLUE (8325 1225);
FORCEPROP 1 LAST VOLTAGE 4V
J 0
(8325 1425);
DISPLAY 0.489362 (8325 1425);
PAINT SKYBLUE (8325 1425);
FORCEPROP 1 LAST PACK_TYPE 0805
J 0
(8325 1275);
DISPLAY 0.489362 (8325 1275);
PAINT SKYBLUE (8325 1275);
FORCEPROP 2 LAST CDS_LIB pure_quanta
J 0
(8275 1400);
DISPLAY INVISIBLE (8275 1400);
FORCEPROP 1 LAST PATH I96
J 0
(8325 1550);
DISPLAY 0.978723 (8325 1550);
PAINT WHITE (8325 1550);
DISPLAY INVISIBLE (8325 1550);
FORCEADD Q_INDUCTOR4P_14..1
(6600 1475);
FORCEPROP 1 LAST LOCATION PL43
J 0
(6375 1730);
DISPLAY 0.489362 (6375 1730);
PAINT SKYBLUE (6375 1730);
FORCEPROP 0 LAST $SEC 1
J 0
(6375 1775);
DISPLAY 0.680851 (6375 1775);
PAINT MONO (6375 1775);
DISPLAY INVISIBLE (6375 1775);
FORCEPROP 0 LAST CDS_SEC 1
J 0
(6375 1775);
DISPLAY 1.021277 (6375 1775);
DISPLAY INVISIBLE (6375 1775);
FORCEPROP 0 LASTPIN (6200 1600) $PN 1
J 2
(6190 1610);
DISPLAY 0.489362 (6190 1610);
PAINT MONO (6190 1610);
FORCEPROP 0 LASTPIN (6200 1350) $PN 2
J 2
(6190 1360);
DISPLAY 0.489362 (6190 1360);
PAINT MONO (6190 1360);
FORCEPROP 0 LASTPIN (7000 1350) $PN 3
J 0
(7010 1360);
DISPLAY 0.489362 (7010 1360);
PAINT MONO (7010 1360);
FORCEPROP 0 LASTPIN (7000 1600) $PN 4
J 0
(7010 1610);
DISPLAY 0.489362 (7010 1610);
PAINT MONO (7010 1610);
FORCEPROP 2 LAST PART_TYPE SMLF
J 0
(6525 1225);
DISPLAY 1.021277 (6525 1225);
FORCEPROP 1 LAST MATERIAL IND
J 0
(6400 1650);
DISPLAY 0.489362 (6400 1650);
PAINT SKYBLUE (6400 1650);
FORCEPROP 2 LAST VALUE 150NH
J 0
(6500 1650);
DISPLAY 0.489362 (6500 1650);
PAINT SKYBLUE (6500 1650);
FORCEPROP 1 LAST PART_NUMBER CV+15^0TZ04
J 0
(6650 1650);
DISPLAY 0.489362 (6650 1650);
PAINT SKYBLUE (6650 1650);
FORCEPROP 1 LAST NEEDS_NO_SIZE TRUE
J 0
(6600 1475);
DISPLAY 0.468085 (6600 1475);
PAINT GREEN (6600 1475);
DISPLAY INVISIBLE (6600 1475);
FORCEPROP 2 LAST CDS_LIB pure_quanta
J 0
(6600 1475);
DISPLAY INVISIBLE (6600 1475);
FORCEPROP 1 LAST PATH I97
J 0
(6800 1630);
DISPLAY 0.723404 (6800 1630);
PAINT GREEN (6800 1630);
DISPLAY INVISIBLE (6800 1630);
FORCEADD Q_INDUCTOR4P_14..1
(6650 4300);
FORCEPROP 1 LAST LOCATION PL44
J 0
(6425 4555);
DISPLAY 0.489362 (6425 4555);
PAINT SKYBLUE (6425 4555);
FORCEPROP 0 LAST $SEC 1
J 0
(6425 4600);
DISPLAY 0.680851 (6425 4600);
PAINT MONO (6425 4600);
DISPLAY INVISIBLE (6425 4600);
FORCEPROP 0 LAST CDS_SEC 1
J 0
(6425 4600);
DISPLAY 1.021277 (6425 4600);
DISPLAY INVISIBLE (6425 4600);
FORCEPROP 0 LASTPIN (6250 4425) $PN 1
J 2
(6240 4435);
DISPLAY 0.489362 (6240 4435);
PAINT MONO (6240 4435);
FORCEPROP 0 LASTPIN (6250 4175) $PN 2
J 2
(6240 4185);
DISPLAY 0.489362 (6240 4185);
PAINT MONO (6240 4185);
FORCEPROP 0 LASTPIN (7050 4175) $PN 3
J 0
(7060 4185);
DISPLAY 0.489362 (7060 4185);
PAINT MONO (7060 4185);
FORCEPROP 0 LASTPIN (7050 4425) $PN 4
J 0
(7060 4435);
DISPLAY 0.489362 (7060 4435);
PAINT MONO (7060 4435);
FORCEPROP 2 LAST PART_TYPE SMLF
J 0
(6575 4050);
DISPLAY 1.021277 (6575 4050);
FORCEPROP 1 LAST MATERIAL IND
J 0
(6450 4475);
DISPLAY 0.489362 (6450 4475);
PAINT SKYBLUE (6450 4475);
FORCEPROP 2 LAST VALUE 150NH
J 0
(6550 4475);
DISPLAY 0.489362 (6550 4475);
PAINT SKYBLUE (6550 4475);
FORCEPROP 1 LAST PART_NUMBER CV+15^0TZ04
J 0
(6700 4475);
DISPLAY 0.489362 (6700 4475);
PAINT SKYBLUE (6700 4475);
FORCEPROP 1 LAST NEEDS_NO_SIZE TRUE
J 0
(6650 4300);
DISPLAY 0.468085 (6650 4300);
PAINT GREEN (6650 4300);
DISPLAY INVISIBLE (6650 4300);
FORCEPROP 2 LAST CDS_LIB pure_quanta
J 0
(6650 4300);
DISPLAY INVISIBLE (6650 4300);
FORCEPROP 1 LAST PATH I98
J 0
(6850 4455);
DISPLAY 0.723404 (6850 4455);
PAINT GREEN (6850 4455);
DISPLAY INVISIBLE (6850 4455);
FORCEADD Q_CAP..1
(825 4050);
FORCEPROP 1 LAST LOCATION PC404_3
J 0
(875 4150);
DISPLAY 0.489362 (875 4150);
PAINT SKYBLUE (875 4150);
FORCEPROP 0 LAST $SEC 1
J 0
(875 4175);
DISPLAY 0.680851 (875 4175);
PAINT MONO (875 4175);
DISPLAY INVISIBLE (875 4175);
FORCEPROP 0 LAST CDS_SEC 1
J 0
(1075 4100);
DISPLAY 1.021277 (1075 4100);
DISPLAY INVISIBLE (1075 4100);
FORCEPROP 1 LASTPIN (825 4150) $PN 1
J 0
(835 4130);
DISPLAY 0.489362 (835 4130);
PAINT MONO (835 4130);
FORCEPROP 1 LASTPIN (825 3950) $PN 2
J 0
(835 3930);
DISPLAY 0.489362 (835 3930);
PAINT MONO (835 3930);
FORCEPROP 1 LAST MATERIAL X7R
J 0
(875 3950);
DISPLAY 0.489362 (875 3950);
PAINT SKYBLUE (875 3950);
FORCEPROP 1 LAST TOLERANCE 10%
J 0
(875 4000);
DISPLAY 0.489362 (875 4000);
PAINT SKYBLUE (875 4000);
FORCEPROP 1 LAST VALUE 0.1UF
J 0
(875 4100);
DISPLAY 0.489362 (875 4100);
PAINT SKYBLUE (875 4100);
FORCEPROP 1 LAST PART_NUMBER CH4104K1B00
J 0
(875 3900);
DISPLAY 0.489362 (875 3900);
PAINT SKYBLUE (875 3900);
FORCEPROP 1 LAST VOLTAGE 25V
J 0
(875 4050);
DISPLAY 0.489362 (875 4050);
PAINT SKYBLUE (875 4050);
FORCEPROP 1 LAST PACK_TYPE 0402
J 0
(875 3850);
DISPLAY 0.489362 (875 3850);
PAINT SKYBLUE (875 3850);
FORCEPROP 2 LAST CDS_LIB pure_quanta
J 0
(825 4050);
DISPLAY INVISIBLE (825 4050);
FORCEPROP 1 LAST PATH I99
J 0
(875 4200);
DISPLAY 0.978723 (875 4200);
PAINT WHITE (875 4200);
DISPLAY INVISIBLE (875 4200);
FORCEADD DNS..1
(4700 4225);
PAINT RED (4700 4225);
FORCEPROP 2 LAST CDS_LIB mstr_misc
J 0
(4700 4225);
DISPLAY INVISIBLE (4700 4225);
FORCEPROP 1 LAST COMMENT_BODY TRUE
R 1
J 0
(4775 4000);
DISPLAY 0.872340 (4775 4000);
PAINT GREEN (4775 4000);
DISPLAY INVISIBLE (4775 4000);
FORCEADD DNS..1
(4600 1400);
PAINT RED (4600 1400);
FORCEPROP 2 LAST CDS_LIB mstr_misc
J 0
(4600 1400);
DISPLAY INVISIBLE (4600 1400);
FORCEPROP 1 LAST COMMENT_BODY TRUE
R 1
J 0
(4675 1175);
DISPLAY 0.872340 (4675 1175);
PAINT GREEN (4675 1175);
DISPLAY INVISIBLE (4675 1175);
FORCEADD DNS..1
(4600 900);
PAINT RED (4600 900);
FORCEPROP 2 LAST CDS_LIB mstr_misc
J 0
(4600 900);
DISPLAY INVISIBLE (4600 900);
FORCEPROP 1 LAST COMMENT_BODY TRUE
R 1
J 0
(4675 675);
DISPLAY 0.872340 (4675 675);
PAINT GREEN (4675 675);
DISPLAY INVISIBLE (4675 675);
FORCEADD QUANTA_TITLE_BLOCK_C..1
(9375 -450);
FORCEPROP 0 LAST CDS_CON_LAST_MODIFIED Fri Mar 11 14:53:36 2022
J 0
(7490 -435);
DISPLAY INVISIBLE (7490 -435);
FORCEPROP 1 LAST CUSTOM_TXT_CDS <CON_LAST_MODIFIED>
J 0
(7490 -435);
DISPLAY 0.978723 (7490 -435);
FORCEPROP 2 LAST CUSTOM_TXT_CDS <XR_PAGE_TITLE>
J 0
(1485 4800);
DISPLAY 0.638298 (1485 4800);
PAINT PINK (1485 4800);
DISPLAY INVISIBLE (1485 4800);
FORCEPROP 1 LAST CUSTOM_TXT_CDS <NAME_2>
J 0
(6200 -400);
FORCEPROP 1 LAST CUSTOM_TXT_CDS <NAME_1>
J 0
(6200 -275);
FORCEPROP 1 LAST CUSTOM_TXT_CDS <Q_NUMBER>
J 0
(7972 -347);
DISPLAY 1.212766 (7972 -347);
FORCEPROP 1 LAST CUSTOM_TXT_CDS <Q_PROJ>
J 0
(6993 -348);
DISPLAY 1.212766 (6993 -348);
FORCEPROP 1 LAST CUSTOM_TXT_CDS <Q_REV>
J 0
(9191 -347);
DISPLAY 1.212766 (9191 -347);
FORCEPROP 1 LAST CUSTOM_TXT_CDS <CON_PAGE_NUM> OF <CON_TOTAL_PAGES>
J 0
(8929 -432);
DISPLAY 0.978723 (8929 -432);
FORCEPROP 1 LAST Q_DEPT BU9
J 1
(5612 -401);
DISPLAY 1.957447 (5612 -401);
PAINT GREEN (5612 -401);
FORCEPROP 1 LAST Q_TITLE PVDDCR_CPU1_P1 VR PHASE 3&4
J 0
(75 -400);
DISPLAY 2.446809 (75 -400);
PAINT GREEN (75 -400);
FORCEPROP 2 LAST PAGE_BORDER TRUE
J 0
(1485 4800);
DISPLAY 0.638298 (1485 4800);
PAINT PINK (1485 4800);
DISPLAY INVISIBLE (1485 4800);
FORCEPROP 2 LAST CDS_LIB pure_quanta
J 0
(9375 -450);
DISPLAY INVISIBLE (9375 -450);
FORCEPROP 1 LAST CDS_LMAN_SYM_OUTLINE -9475,6775,100,-125
J 0
(9375 -450);
DISPLAY 0.468085 (9375 -450);
PAINT GREEN (9375 -450);
DISPLAY INVISIBLE (9375 -450);
FORCEPROP 1 LAST COMMENT_BODY TRUE
J 0
(9387 -463);
DISPLAY 0.978723 (9387 -463);
PAINT GREEN (9387 -463);
DISPLAY INVISIBLE (9387 -463);
FORCEPROP 2 LAST CDS_XR_PAGE_TITLE CR-195 : @T6G_MB_LIB.T6G(SCH_1):PAGE195
J 0
(1485 4800);
DISPLAY 0.638298 (1485 4800);
PAINT PINK (1485 4800);
DISPLAY INVISIBLE (1485 4800);
FORCEADD DNS..1
(1300 1075);
PAINT RED (1300 1075);
FORCEPROP 2 LAST CDS_LIB mstr_misc
J 0
(1300 1075);
PAINT MONO (1300 1075);
DISPLAY INVISIBLE (1300 1075);
FORCEPROP 1 LAST COMMENT_BODY TRUE
R 1
J 0
(1375 850);
DISPLAY 0.872340 (1375 850);
PAINT GREEN (1375 850);
DISPLAY INVISIBLE (1375 850);
FORCEADD DNS..1
(1325 3900);
PAINT RED (1325 3900);
FORCEPROP 2 LAST CDS_LIB mstr_misc
J 0
(1325 3900);
PAINT MONO (1325 3900);
DISPLAY INVISIBLE (1325 3900);
FORCEPROP 1 LAST COMMENT_BODY TRUE
R 1
J 0
(1400 3675);
DISPLAY 0.872340 (1400 3675);
PAINT GREEN (1400 3675);
DISPLAY INVISIBLE (1400 3675);
FORCEADD DNS..1
(4700 3675);
PAINT RED (4700 3675);
FORCEPROP 2 LAST CDS_LIB mstr_misc
J 0
(4700 3675);
DISPLAY INVISIBLE (4700 3675);
FORCEPROP 1 LAST COMMENT_BODY TRUE
R 1
J 0
(4775 3450);
DISPLAY 0.872340 (4775 3450);
PAINT GREEN (4775 3450);
DISPLAY INVISIBLE (4775 3450);
WIRE 16 -1 (1300 1000)(1300 925);
WIRE 16 -1 (1625 4775)(1625 4725);
WIRE 16 -1 (1975 5350)(1975 5225);
WIRE 16 -1 (1325 3825)(1325 3750);
WIRE 16 -1 (1450 1950)(1450 1900);
WIRE 16 -1 (1800 2525)(1800 2400);
WIRE 16 -1 (825 3900)(825 3950);
WIRE 16 -1 (800 1075)(800 1125);
WIRE 16 -1 (4725 3575)(4725 3500);
WIRE 16 -1 (4625 800)(4625 725);
WIRE 16 -1 (4725 4775)(5600 4775);
FORCEPROP 2 LAST SIG_NAME SW_PVDDCR_CPU1_P1_BOOT3_R
J 0
(4840 4785);
DISPLAY 0.489362 (4840 4785);
FORCEPROP 2 LASTPROP $XRERR UNIQUE?
J 0
(4600 4785);
DISPLAY 0.638298 (4600 4785);
PAINT MONO (4600 4785);
DISPLAY INVISIBLE (4600 4785);
WIRE 16 -1 (5600 4775)(5600 4750);
WIRE 16 -1 (5650 5050)(5650 5100);
WIRE 16 -1 (5650 5250)(5650 5100);
WIRE 16 -1 (5275 5100)(5650 5100);
WIRE 16 -1 (5275 5250)(5275 5100);
WIRE 16 -1 (4875 5100)(5275 5100);
WIRE 16 -1 (4875 5250)(4875 5100);
WIRE 16 -1 (4875 5100)(4475 5100);
WIRE 16 -1 (4475 5250)(4475 5100);
WIRE 16 -1 (4075 5100)(4475 5100);
WIRE 16 -1 (4075 5275)(4075 5100);
WIRE 16 -1 (3650 4425)(4725 4425);
FORCEPROP 2 LAST SIG_NAME SW_PVDDCR_CPU1_P1_SW3
J 0
(3840 4435);
DISPLAY 0.489362 (3840 4435);
FORCEPROP 2 LASTPROP $XRERR UNIQUE?
J 0
(3600 4435);
DISPLAY 0.638298 (3600 4435);
PAINT MONO (3600 4435);
DISPLAY INVISIBLE (3600 4435);
WIRE 16 -1 (4725 4425)(6250 4425);
WIRE 16 -1 (4725 4325)(4725 4425);
WIRE 16 -1 (3650 4525)(5600 4525);
FORCEPROP 2 LAST SIG_NAME SW_PVDDCR_CPU1_P1_BOOTR3
J 0
(3840 4535);
DISPLAY 0.489362 (3840 4535);
FORCEPROP 2 LASTPROP $XRERR UNIQUE?
J 0
(3600 4535);
DISPLAY 0.638298 (3600 4535);
PAINT MONO (3600 4535);
DISPLAY INVISIBLE (3600 4535);
WIRE 16 -1 (5600 4525)(5600 4550);
WIRE 16 -1 (3625 1700)(5450 1700);
FORCEPROP 2 LAST SIG_NAME SW_PVDDCR_CPU1_P1_BOOTR4
J 0
(3815 1710);
DISPLAY 0.489362 (3815 1710);
FORCEPROP 2 LASTPROP $XRERR UNIQUE?
J 0
(3575 1710);
DISPLAY 0.638298 (3575 1710);
PAINT MONO (3575 1710);
DISPLAY INVISIBLE (3575 1710);
WIRE 16 -1 (5450 1700)(5450 1725);
WIRE 16 -1 (4625 1500)(4625 1600);
WIRE 16 -1 (4625 1600)(6200 1600);
WIRE 16 -1 (3625 1600)(4625 1600);
FORCEPROP 2 LAST SIG_NAME SW_PVDDCR_CPU1_P1_SW4
J 0
(3815 1610);
DISPLAY 0.489362 (3815 1610);
FORCEPROP 2 LASTPROP $XRERR UNIQUE?
J 0
(3575 1610);
DISPLAY 0.638298 (3575 1610);
PAINT MONO (3575 1610);
DISPLAY INVISIBLE (3575 1610);
WIRE 16 -1 (1450 2225)(2025 2225);
WIRE 16 -1 (1450 2500)(1450 2225);
WIRE 16 -1 (1450 2225)(1450 2150);
WIRE 16 -1 (2025 2225)(2025 1950);
WIRE 16 -1 (2675 1950)(2025 1950);
FORCEPROP 2 LAST SIG_NAME PVDDCR_CPU1_P1_VCC4
J 0
(2140 1960);
DISPLAY 0.489362 (2140 1960);
FORCEPROP 2 LASTPROP $XRERR UNIQUE?
J 0
(1900 1960);
DISPLAY 0.638298 (1900 1960);
PAINT MONO (1900 1960);
DISPLAY INVISIBLE (1900 1960);
WIRE 16 -1 (2775 1950)(2675 1950);
WIRE 16 -1 (2675 1750)(2675 1950);
WIRE 16 -1 (2775 1750)(2675 1750);
WIRE 16 -1 (1450 2700)(1450 2825);
WIRE 16 -1 (1800 2825)(1450 2825);
WIRE 16 -1 (1450 2950)(1450 2825);
WIRE 16 -1 (2700 2825)(1800 2825);
WIRE 16 -1 (1800 2725)(1800 2825);
WIRE 16 -1 (2700 2250)(2700 2825);
WIRE 16 -1 (2775 2250)(2700 2250);
WIRE 16 -1 (2675 1425)(800 1425);
WIRE 16 -1 (2675 1500)(2675 1425);
FORCEPROP 0 LAST CDS_PHYS_NET_NAME PVCCIN_CPU0_VREF
J 0
(2675 1450);
PAINT MONO (2675 1450);
DISPLAY INVISIBLE (2675 1450);
WIRE 16 -1 (800 1425)(800 1325);
WIRE 16 -1 (1825 1500)(2675 1500);
FORCEPROP 2 LAST SIG_NAME PVDDCR_CPU1_P1_VCCS
J 0
(1940 1510);
DISPLAY 0.489362 (1940 1510);
WIRE 16 -1 (2675 1500)(2775 1500);
WIRE 16 -1 (1300 1300)(2775 1300);
FORCEPROP 2 LAST SIG_NAME PVDDCR_CPU1_P1_LSET4
J 0
(1940 1310);
DISPLAY 0.489362 (1940 1310);
FORCEPROP 2 LASTPROP $XRERR UNIQUE?
J 0
(1700 1310);
DISPLAY 0.638298 (1700 1310);
PAINT MONO (1700 1310);
DISPLAY INVISIBLE (1700 1310);
WIRE 16 -1 (1300 1300)(1300 1200);
WIRE 16 -1 (2800 3825)(1850 3825);
FORCEPROP 2 LAST SIG_NAME PVDDCR_CPU1_P1_PWM3
J 0
(1965 3835);
DISPLAY 0.489362 (1965 3835);
WIRE 16 -1 (2800 3925)(1850 3925);
FORCEPROP 2 LAST SIG_NAME PVDDCR_CPU1_P1_TEMP0
J 0
(1965 3935);
DISPLAY 0.489362 (1965 3935);
WIRE 16 -1 (2775 1100)(1825 1100);
FORCEPROP 2 LAST SIG_NAME PVDDCR_CPU1_P1_TEMP0
J 0
(1940 1110);
DISPLAY 0.489362 (1940 1110);
WIRE 16 -1 (2775 1000)(1825 1000);
FORCEPROP 2 LAST SIG_NAME PVDDCR_CPU1_P1_PWM4
J 0
(1940 1010);
DISPLAY 0.489362 (1940 1010);
WIRE 16 -1 (2775 1600)(1825 1600);
FORCEPROP 2 LAST SIG_NAME PVDDCR_CPU1_P1_IMON4
J 0
(1940 1610);
DISPLAY 0.489362 (1940 1610);
WIRE 16 -1 (2775 1350)(2400 1350);
FORCEPROP 2 LAST SIG_NAME NC_PVDDCR_CPU1_P1_DNC4
J 0
(2205 1360);
DISPLAY 0.489362 (2205 1360);
FORCEPROP 2 LASTPROP $XRERR UNIQUE?
J 0
(2160 1350);
DISPLAY 0.638298 (2160 1350);
PAINT MONO (2160 1350);
DISPLAY INVISIBLE (2160 1350);
WIRE 16 -1 (3875 1050)(3875 1000);
WIRE 16 -1 (3875 1100)(3875 1050);
WIRE 16 -1 (3625 1050)(3875 1050);
WIRE 16 -1 (3875 1000)(3875 925);
WIRE 16 -1 (3625 1000)(3875 1000);
WIRE 16 -1 (3625 1100)(3875 1100);
WIRE 16 -1 (3875 1150)(3875 1100);
WIRE 16 -1 (3625 1150)(3875 1150);
WIRE 16 -1 (3625 2200)(3800 2200);
WIRE 16 -1 (3800 2200)(3800 2250);
WIRE 16 -1 (3800 2750)(3800 2250);
WIRE 16 -1 (3625 2250)(3800 2250);
WIRE 16 -1 (4025 2750)(3800 2750);
WIRE 16 -1 (4425 2750)(4025 2750);
WIRE 16 -1 (4025 2625)(4025 2750);
WIRE 16 -1 (4425 2750)(4825 2750);
WIRE 16 -1 (4425 2600)(4425 2750);
WIRE 16 -1 (4825 2750)(5225 2750);
WIRE 16 -1 (4825 2750)(4825 2600);
WIRE 16 -1 (5225 2750)(5600 2750);
WIRE 16 -1 (5225 2600)(5225 2750);
WIRE 16 -1 (5600 2800)(5600 2750);
WIRE 16 -1 (5600 2600)(5600 2750);
WIRE 16 -1 (3900 3875)(3900 3825);
WIRE 16 -1 (3650 3875)(3900 3875);
WIRE 16 -1 (3900 3925)(3900 3875);
WIRE 16 -1 (3900 3825)(3900 3750);
WIRE 16 -1 (3650 3825)(3900 3825);
WIRE 16 -1 (3650 3925)(3900 3925);
WIRE 16 -1 (3900 3975)(3900 3925);
WIRE 16 -1 (3650 3975)(3900 3975);
WIRE 16 -1 (1625 5525)(1625 5650);
WIRE 16 -1 (1975 5650)(1625 5650);
WIRE 16 -1 (1625 5775)(1625 5650);
WIRE 16 -1 (1975 5550)(1975 5650);
WIRE 16 -1 (2300 5650)(1975 5650);
WIRE 16 -1 (2300 5075)(2300 5650);
WIRE 16 -1 (2800 5075)(2300 5075);
WIRE 16 -1 (1325 4125)(2800 4125);
FORCEPROP 2 LAST SIG_NAME PVDDCR_CPU1_P1_LSET3
J 0
(1965 4135);
DISPLAY 0.489362 (1965 4135);
FORCEPROP 2 LASTPROP $XRERR UNIQUE?
J 0
(1725 4135);
DISPLAY 0.638298 (1725 4135);
PAINT MONO (1725 4135);
DISPLAY INVISIBLE (1725 4135);
WIRE 16 -1 (1325 4125)(1325 4025);
WIRE 16 -1 (1625 4975)(1625 5075);
WIRE 16 -1 (1625 5075)(2075 5075);
WIRE 16 -1 (1625 5325)(1625 5075);
WIRE 16 -1 (2075 5075)(2075 4775);
WIRE 16 -1 (2700 4775)(2075 4775);
FORCEPROP 2 LAST SIG_NAME PVDDCR_CPU1_P1_VCC3
J 0
(2165 4785);
DISPLAY 0.489362 (2165 4785);
FORCEPROP 2 LASTPROP $XRERR UNIQUE?
J 0
(1925 4785);
DISPLAY 0.638298 (1925 4785);
PAINT MONO (1925 4785);
DISPLAY INVISIBLE (1925 4785);
WIRE 16 -1 (2700 4775)(2800 4775);
WIRE 16 -1 (2700 4575)(2700 4775);
WIRE 16 -1 (2800 4575)(2700 4575);
WIRE 16 -1 (2700 4250)(825 4250);
WIRE 16 -1 (2700 4325)(2700 4250);
FORCEPROP 0 LAST CDS_PHYS_NET_NAME PVCCIN_CPU0_VREF
J 0
(2700 4275);
PAINT MONO (2700 4275);
DISPLAY INVISIBLE (2700 4275);
WIRE 16 -1 (825 4250)(825 4150);
WIRE 16 -1 (1850 4325)(2700 4325);
FORCEPROP 2 LAST SIG_NAME PVDDCR_CPU1_P1_VCCS
J 0
(1965 4335);
DISPLAY 0.489362 (1965 4335);
WIRE 16 -1 (2700 4325)(2800 4325);
WIRE 16 -1 (2800 4425)(1850 4425);
FORCEPROP 2 LAST SIG_NAME PVDDCR_CPU1_P1_IMON3
J 0
(1965 4435);
DISPLAY 0.489362 (1965 4435);
WIRE 16 -1 (2800 4175)(2425 4175);
FORCEPROP 2 LAST SIG_NAME NC_PVDDCR_CPU1_P1_DNC3
J 0
(2230 4185);
DISPLAY 0.489362 (2230 4185);
FORCEPROP 2 LASTPROP $XRERR UNIQUE?
J 0
(2185 4175);
DISPLAY 0.638298 (2185 4175);
PAINT MONO (2185 4175);
DISPLAY INVISIBLE (2185 4175);
WIRE 16 -1 (3650 5025)(3825 5025);
WIRE 16 -1 (3825 5025)(3825 5075);
WIRE 16 -1 (3825 5600)(3825 5075);
WIRE 16 -1 (3650 5075)(3825 5075);
WIRE 16 -1 (4075 5600)(3825 5600);
WIRE 16 -1 (4475 5600)(4075 5600);
WIRE 16 -1 (4075 5475)(4075 5600);
WIRE 16 -1 (4475 5600)(4875 5600);
WIRE 16 -1 (4475 5450)(4475 5600);
WIRE 16 -1 (4875 5600)(5275 5600);
WIRE 16 -1 (4875 5600)(4875 5450);
WIRE 16 -1 (5275 5600)(5650 5600);
WIRE 16 -1 (5275 5450)(5275 5600);
WIRE 16 -1 (5650 5650)(5650 5600);
WIRE 16 -1 (5650 5450)(5650 5600);
WIRE 16 -1 (4175 4075)(3650 4075);
FORCEPROP 2 LAST SIG_NAME NC_PVDDCR_CPU1_P1_GL2_3
J 0
(3740 4085);
DISPLAY 0.489362 (3740 4085);
FORCEPROP 2 LASTPROP $XRERR UNIQUE?
J 0
(4205 4075);
DISPLAY 0.638298 (4205 4075);
PAINT MONO (4205 4075);
DISPLAY INVISIBLE (4205 4075);
WIRE 16 -1 (4175 4125)(3650 4125);
FORCEPROP 2 LAST SIG_NAME NC_PVDDCR_CPU1_P1_GL1_3
J 0
(3740 4135);
DISPLAY 0.489362 (3740 4135);
FORCEPROP 2 LASTPROP $XRERR UNIQUE?
J 0
(4205 4125);
DISPLAY 0.638298 (4205 4125);
PAINT MONO (4205 4125);
DISPLAY INVISIBLE (4205 4125);
WIRE 16 -1 (3650 4775)(4525 4775);
FORCEPROP 2 LAST SIG_NAME SW_PVDDCR_CPU1_P1_BOOT3
J 0
(3815 4785);
DISPLAY 0.489362 (3815 4785);
FORCEPROP 2 LASTPROP $XRERR UNIQUE?
J 0
(3575 4785);
DISPLAY 0.638298 (3575 4785);
PAINT MONO (3575 4785);
DISPLAY INVISIBLE (3575 4785);
WIRE 16 -1 (3625 1950)(4450 1950);
FORCEPROP 2 LAST SIG_NAME SW_PVDDCR_CPU1_P1_BOOT4
J 0
(3790 1960);
DISPLAY 0.489362 (3790 1960);
FORCEPROP 2 LASTPROP $XRERR UNIQUE?
J 0
(3550 1960);
DISPLAY 0.638298 (3550 1960);
PAINT MONO (3550 1960);
DISPLAY INVISIBLE (3550 1960);
WIRE 16 -1 (3625 1300)(4200 1300);
FORCEPROP 2 LAST SIG_NAME NC_PVDDCR_CPU1_P1_GL1_4
J 0
(3740 1310);
DISPLAY 0.489362 (3740 1310);
FORCEPROP 2 LASTPROP $XRERR UNIQUE?
J 0
(4230 1300);
DISPLAY 0.638298 (4230 1300);
PAINT MONO (4230 1300);
DISPLAY INVISIBLE (4230 1300);
WIRE 16 -1 (3625 1250)(4200 1250);
FORCEPROP 2 LAST SIG_NAME NC_PVDDCR_CPU1_P1_GL2_4
J 0
(3740 1260);
DISPLAY 0.489362 (3740 1260);
FORCEPROP 2 LASTPROP $XRERR UNIQUE?
J 0
(4230 1250);
DISPLAY 0.638298 (4230 1250);
PAINT MONO (4230 1250);
DISPLAY INVISIBLE (4230 1250);
WIRE 16 -1 (4025 2425)(4025 2250);
WIRE 16 -1 (4025 2250)(4425 2250);
WIRE 16 -1 (4825 2250)(4425 2250);
WIRE 16 -1 (4425 2400)(4425 2250);
WIRE 16 -1 (4825 2250)(5225 2250);
WIRE 16 -1 (4825 2400)(4825 2250);
WIRE 16 -1 (5225 2250)(5600 2250);
WIRE 16 -1 (5225 2400)(5225 2250);
WIRE 16 -1 (5600 2400)(5600 2250);
WIRE 16 -1 (5600 2175)(5600 2250);
WIRE 16 -1 (4625 1300)(4625 1000);
FORCEPROP 2 LAST SIG_NAME SW_PVDDCR_CPU1_P1_SW4_RC
J 0
(4665 1110);
DISPLAY 0.489362 (4665 1110);
FORCEPROP 2 LASTPROP $XRERR UNIQUE?
J 0
(4425 1110);
DISPLAY 0.638298 (4425 1110);
PAINT MONO (4425 1110);
DISPLAY INVISIBLE (4425 1110);
WIRE 16 -1 (3625 1350)(4400 1350);
FORCEPROP 2 LAST SIG_NAME PVDDCR_CPU1_P1_VOS4
J 0
(3740 1375);
DISPLAY 0.489362 (3740 1375);
FORCEPROP 2 LASTPROP $XRERR UNIQUE?
J 0
(3500 1375);
DISPLAY 0.638298 (3500 1375);
PAINT MONO (3500 1375);
DISPLAY INVISIBLE (3500 1375);
WIRE 16 -1 (4400 1350)(4400 600);
WIRE 16 -1 (4400 600)(5825 600);
WIRE 16 -1 (4650 1950)(5450 1950);
FORCEPROP 2 LAST SIG_NAME SW_PVDDCR_CPU1_P1_BOOT4_R
J 0
(4865 1960);
DISPLAY 0.489362 (4865 1960);
FORCEPROP 2 LASTPROP $XRERR UNIQUE?
J 0
(4625 1960);
DISPLAY 0.638298 (4625 1960);
PAINT MONO (4625 1960);
DISPLAY INVISIBLE (4625 1960);
WIRE 16 -1 (5450 1950)(5450 1925);
WIRE 16 -1 (5675 1350)(6200 1350);
FORCEPROP 2 LAST SIG_NAME IND_CPU1_P1_CPL3
J 0
(5740 1360);
DISPLAY 0.489362 (5740 1360);
WIRE 16 -1 (7825 600)(7825 1600);
WIRE 16 -1 (7825 600)(6025 600);
WIRE 16 -1 (7000 1600)(7825 1600);
WIRE 16 -1 (7825 1600)(8275 1600);
WIRE 16 -1 (8275 1600)(8700 1600);
WIRE 16 -1 (8275 1600)(8275 1500);
WIRE 16 -1 (8700 1650)(8700 1600);
WIRE 16 -1 (8700 1600)(8700 1500);
WIRE 16 -1 (7475 1300)(7475 1350);
WIRE 16 -1 (7000 1350)(7475 1350);
WIRE 16 -1 (4425 4175)(4425 3250);
FORCEPROP 2 LAST SIG_NAME PVDDCR_CPU1_P1_VOS3
J 0
(3740 4200);
DISPLAY 0.489362 (3740 4200);
FORCEPROP 2 LASTPROP $XRERR UNIQUE?
J 0
(3500 4200);
DISPLAY 0.638298 (3500 4200);
PAINT MONO (3500 4200);
DISPLAY INVISIBLE (3500 4200);
WIRE 16 -1 (3650 4175)(4425 4175);
WIRE 16 -1 (4425 3250)(5750 3250);
WIRE 16 -1 (4725 4125)(4725 3775);
FORCEPROP 2 LAST SIG_NAME SW_PVDDCR_CPU1_P1_SW3_RC
J 0
(4765 3910);
DISPLAY 0.489362 (4765 3910);
FORCEPROP 2 LASTPROP $XRERR UNIQUE?
J 0
(4525 3910);
DISPLAY 0.638298 (4525 3910);
PAINT MONO (4525 3910);
DISPLAY INVISIBLE (4525 3910);
WIRE 16 -1 (5950 3250)(8000 3250);
WIRE 16 -1 (8000 3250)(8000 4425);
WIRE 16 -1 (8125 4425)(8000 4425);
WIRE 16 -1 (8000 4425)(7050 4425);
WIRE 16 -1 (8125 4425)(8550 4425);
WIRE 16 -1 (8125 4425)(8125 4325);
WIRE 16 -1 (8550 4475)(8550 4425);
WIRE 16 -1 (8550 4325)(8550 4425);
WIRE 16 -1 (5600 4175)(6250 4175);
FORCEPROP 2 LAST SIG_NAME IND_CPU1_P1_CPL2
J 0
(5765 4185);
DISPLAY 0.489362 (5765 4185);
WIRE 16 -1 (7050 4175)(7575 4175);
FORCEPROP 2 LAST SIG_NAME IND_CPU1_P1_CPL3
J 0
(7140 4185);
DISPLAY 0.489362 (7140 4185);
WIRE 16 -1 (8550 4000)(8125 4000);
WIRE 16 -1 (8550 4125)(8550 4000);
WIRE 16 -1 (8550 3950)(8550 4000);
WIRE 16 -1 (8125 4000)(8125 4125);
WIRE 16 -1 (8700 1175)(8275 1175);
WIRE 16 -1 (8700 1175)(8700 1300);
WIRE 16 -1 (8700 1125)(8700 1175);
WIRE 16 -1 (8275 1175)(8275 1300);
DOT 1 (7825 1600);
DOT 1 (5600 2750);
DOT 1 (4425 2250);
DOT 1 (5225 2250);
DOT 1 (4475 5100);
DOT 1 (4875 5100);
DOT 1 (4475 5600);
DOT 1 (3875 1050);
DOT 1 (3875 1000);
DOT 1 (1450 2225);
DOT 1 (1450 2825);
DOT 1 (2675 1500);
DOT 1 (2675 1950);
DOT 1 (3875 1100);
DOT 1 (3800 2250);
DOT 1 (3900 3825);
DOT 1 (3900 3875);
DOT 1 (3900 3925);
DOT 1 (1625 5075);
DOT 1 (1625 5650);
DOT 1 (1975 5650);
DOT 1 (4075 5600);
DOT 1 (4425 2750);
DOT 1 (4825 2250);
DOT 1 (4825 2750);
DOT 1 (5600 2250);
DOT 1 (5225 2750);
DOT 1 (4875 5600);
DOT 1 (5275 5100);
DOT 1 (5650 5100);
DOT 1 (5275 5600);
DOT 1 (5650 5600);
DOT 1 (8550 4425);
DOT 1 (8125 4425);
DOT 1 (8550 4000);
DOT 1 (8000 4425);
DOT 1 (8700 1600);
DOT 1 (8700 1175);
DOT 1 (8275 1600);
DOT 1 (2700 4325);
DOT 1 (2700 4775);
DOT 1 (3825 5075);
DOT 1 (4025 2750);
DOT 1 (1800 2825);
DOT 1 (4725 4425);
DOT 1 (4625 1600);
FORCENOTE
DCR=2-3,0.27M OHM
(7175 4475) 0;
DISPLAY LEFT (7175 4475);
DISPLAY 0.638298 (7175 4475);
PAINT WHITE (7175 4475);
FORCENOTE
DCR=1-4,0.105M OHM
(7175 4525) 0;
DISPLAY LEFT (7175 4525);
DISPLAY 0.638298 (7175 4525);
PAINT WHITE (7175 4525);
FORCENOTE
11.0*7.5*12.5
(7175 4575) 0;
DISPLAY LEFT (7175 4575);
DISPLAY 0.638298 (7175 4575);
PAINT WHITE (7175 4575);
FORCENOTE
ISAT:70A@100C
(7175 4625) 0;
DISPLAY LEFT (7175 4625);
DISPLAY 0.638298 (7175 4625);
PAINT WHITE (7175 4625);
FORCENOTE
PGL6303.151HLT
(7175 4675) 0;
DISPLAY LEFT (7175 4675);
DISPLAY 0.638298 (7175 4675);
PAINT WHITE (7175 4675);
FORCENOTE
ISAT:70A@100C
(7075 1825) 0;
DISPLAY LEFT (7075 1825);
DISPLAY 0.638298 (7075 1825);
PAINT WHITE (7075 1825);
FORCENOTE
PGL6303.151HLT
(7075 1875) 0;
DISPLAY LEFT (7075 1875);
DISPLAY 0.638298 (7075 1875);
PAINT WHITE (7075 1875);
FORCENOTE
DCR=2-3,0.27M OHM
(7075 1675) 0;
DISPLAY LEFT (7075 1675);
DISPLAY 0.638298 (7075 1675);
PAINT WHITE (7075 1675);
FORCENOTE
DCR=1-4,0.105M OHM
(7075 1725) 0;
DISPLAY LEFT (7075 1725);
DISPLAY 0.638298 (7075 1725);
PAINT WHITE (7075 1725);
FORCENOTE
11.0*7.5*12.5
(7075 1775) 0;
DISPLAY LEFT (7075 1775);
DISPLAY 0.638298 (7075 1775);
PAINT WHITE (7075 1775);
FORCENOTE
PVDDCR_CPU1_P1_PHASE4
(2850 2775) 0;
DISPLAY LEFT (2850 2775);
DISPLAY 1.021277 (2850 2775);
PAINT WHITE (2850 2775);
FORCENOTE
PVDDCR_CPU1_P1_PHASE3
(2875 5600) 0;
DISPLAY LEFT (2875 5600);
DISPLAY 1.021277 (2875 5600);
PAINT WHITE (2875 5600);
QUIT
